FILE_TYPE = MACRO_DRAWING;
SET COLOR_WIRE YELLOW;
SET COLOR_PROP MONO;
SET COLOR_DOT WHITE;
SET COLOR_ARC YELLOW;
SET COLOR_BODY GREEN;
SET COLOR_NOTE MONO;
SET PROP_DISPLAY VALUE;
SET PAGE_NUMBER P228;
FORCEADD PVDDQ_KLM..1
(2525 1700);
FORCEPROP 3 LASTPIN (2525 1650) SIG_NAME PVDDQ_KLM\g
J 0
(2535 1660);
DISPLAY 0.659574 (2535 1660);
PAINT MONO (2535 1660);
DISPLAY INVISIBLE (2535 1660);
FORCEPROP 2 LAST BOM_COST MEM_VRD_PVDDQ_CD
J 0
(2600 1800);
PAINT MONO (2600 1800);
DISPLAY INVISIBLE (2600 1800);
FORCEPROP 1 LAST PATH I109
J 0
(2575 1725);
DISPLAY 0.872340 (2575 1725);
PAINT AQUA (2575 1725);
DISPLAY INVISIBLE (2575 1725);
FORCEPROP 2 LAST ROOM VDDQ_KLM_PWR_VR
J 0
(2775 1800);
PAINT ORANGE (2775 1800);
DISPLAY INVISIBLE (2775 1800);
FORCEPROP 2 LAST CDS_LIB mstr_symbols
J 0
(2525 1700);
PAINT ORANGE (2525 1700);
DISPLAY INVISIBLE (2525 1700);
FORCEPROP 1 LAST VOLTAGE 1.2V
J 0
(2480 1657);
DISPLAY 0.340426 (2480 1657);
PAINT SKYBLUE (2480 1657);
DISPLAY INVISIBLE (2480 1657);
FORCEPROP 1 LAST BODY_TYPE PLUMBING
J 0
(2480 1657);
DISPLAY 0.340426 (2480 1657);
PAINT GREEN (2480 1657);
DISPLAY INVISIBLE (2480 1657);
FORCEPROP 1 LAST HDL_POWER PVDDQ_KLM
J 1
(2525 1750);
DISPLAY 0.872340 (2525 1750);
PAINT GREEN (2525 1750);
DISPLAY INVISIBLE (2525 1750);
FORCEADD GND..1
(4250 1050);
FORCEPROP 3 LASTPIN (4250 1100) SIG_NAME GND\g
J 0
(4260 1110);
DISPLAY 0.659574 (4260 1110);
PAINT MONO (4260 1110);
DISPLAY INVISIBLE (4260 1110);
FORCEPROP 1 LAST VOLTAGE 0
J 0
(4250 1050);
PAINT SKYBLUE (4250 1050);
DISPLAY INVISIBLE (4250 1050);
FORCEPROP 2 LAST CDS_LIB mstr_symbols
J 0
(4250 1050);
PAINT ORANGE (4250 1050);
DISPLAY INVISIBLE (4250 1050);
FORCEPROP 1 LAST PATH I114
J 0
(4325 1050);
DISPLAY 1.170213 (4325 1050);
PAINT AQUA (4325 1050);
DISPLAY INVISIBLE (4325 1050);
FORCEPROP 1 LAST SIZE 1B
J 0
(4325 1000);
DISPLAY 0.893617 (4325 1000);
PAINT GREEN (4325 1000);
DISPLAY INVISIBLE (4325 1000);
FORCEPROP 2 LAST BOM_COST MEM_VRD_PVDDQ_CD
J 0
(3925 1125);
PAINT MONO (3925 1125);
DISPLAY INVISIBLE (3925 1125);
FORCEPROP 2 LAST ROOM VDDQ_KLM_PWR_VR
J 0
(3700 1125);
PAINT ORANGE (3700 1125);
DISPLAY INVISIBLE (3700 1125);
FORCEPROP 1 LAST BODY_TYPE PLUMBING
J 0
(4205 1007);
DISPLAY 0.340426 (4205 1007);
PAINT GREEN (4205 1007);
DISPLAY INVISIBLE (4205 1007);
FORCEPROP 1 LAST HDL_POWER GND
J 0
(4250 1200);
DISPLAY 0.893617 (4250 1200);
PAINT GREEN (4250 1200);
DISPLAY INVISIBLE (4250 1200);
FORCEADD VCC_CORE..1
(-675 1350);
FORCEPROP 3 LASTPIN (-675 1300) SIG_NAME VR_FET_SW_P12V_STBY_PVDDQ_KLM\g
J 0
(-665 1310);
DISPLAY 0.659574 (-665 1310);
PAINT MONO (-665 1310);
DISPLAY INVISIBLE (-665 1310);
FORCEPROP 1 LAST HDL_POWER VR_FET_SW_P12V_STBY_PVDDQ_KLM
J 1
(-675 1400);
DISPLAY 0.617021 (-675 1400);
PAINT GREEN (-675 1400);
FORCEPROP 1 LAST PATH I120
J 0
(-625 1375);
DISPLAY 1.170213 (-625 1375);
PAINT AQUA (-625 1375);
DISPLAY INVISIBLE (-625 1375);
FORCEPROP 2 LAST CDS_LIB mstr_symbols
J 0
(-675 1350);
PAINT ORANGE (-675 1350);
DISPLAY INVISIBLE (-675 1350);
FORCEADD GND..1
(-675 675);
FORCEPROP 3 LASTPIN (-675 725) SIG_NAME GND\g
J 0
(-665 735);
DISPLAY 0.659574 (-665 735);
PAINT MONO (-665 735);
DISPLAY INVISIBLE (-665 735);
FORCEPROP 1 LAST PATH I123
J 0
(-600 675);
DISPLAY 1.170213 (-600 675);
PAINT AQUA (-600 675);
DISPLAY INVISIBLE (-600 675);
FORCEPROP 2 LAST CDS_LIB mstr_symbols
J 0
(-675 675);
PAINT ORANGE (-675 675);
DISPLAY INVISIBLE (-675 675);
FORCEPROP 1 LAST SIZE 1B
J 0
(-600 625);
DISPLAY 0.893617 (-600 625);
PAINT GREEN (-600 625);
DISPLAY INVISIBLE (-600 625);
FORCEPROP 1 LAST VOLTAGE 0
J 0
(-675 675);
PAINT SKYBLUE (-675 675);
DISPLAY INVISIBLE (-675 675);
FORCEPROP 2 LAST BOM_COST MEM_VRD_PVDDQ_CD
J 0
(-1000 750);
PAINT MONO (-1000 750);
DISPLAY INVISIBLE (-1000 750);
FORCEPROP 2 LAST ROOM VDDQ_KLM_PWR_VR
J 0
(-1225 750);
PAINT ORANGE (-1225 750);
DISPLAY INVISIBLE (-1225 750);
FORCEPROP 1 LAST BODY_TYPE PLUMBING
J 0
(-720 632);
DISPLAY 0.340426 (-720 632);
PAINT GREEN (-720 632);
DISPLAY INVISIBLE (-720 632);
FORCEPROP 1 LAST HDL_POWER GND
J 0
(-675 825);
DISPLAY 0.893617 (-675 825);
PAINT GREEN (-675 825);
DISPLAY INVISIBLE (-675 825);
FORCEADD CAPP..1
(-675 900);
FORCEPROP 1 LASTPIN (-675 1000) $PN 1
J 0
(-665 985);
DISPLAY 0.617021 (-665 985);
PAINT ORANGE (-665 985);
FORCEPROP 1 LASTPIN (-675 800) $PN 2
J 0
(-665 785);
DISPLAY 0.617021 (-665 785);
PAINT ORANGE (-665 785);
FORCEPROP 1 LAST TOLERANCE 20%
J 0
(-625 900);
DISPLAY 0.617021 (-625 900);
PAINT SKYBLUE (-625 900);
FORCEPROP 1 LAST VOLTAGE 16V
J 0
(-625 850);
DISPLAY 0.617021 (-625 850);
PAINT SKYBLUE (-625 850);
FORCEPROP 1 LAST VALUE 270UF
J 0
(-625 950);
DISPLAY 0.617021 (-625 950);
PAINT SKYBLUE (-625 950);
FORCEPROP 1 LAST MATERIAL OSCON
J 0
(-625 800);
DISPLAY 0.617021 (-625 800);
PAINT SKYBLUE (-625 800);
FORCEPROP 1 LAST PACK_TYPE 2626
J 0
(-625 750);
DISPLAY 0.617021 (-625 750);
PAINT SKYBLUE (-625 750);
FORCEPROP 1 LAST LOCATION C1B10
J 0
(-625 1000);
DISPLAY 0.617021 (-625 1000);
PAINT AQUA (-625 1000);
FORCEPROP 1 LAST PART_NUMBER A31228-047
J 0
(-625 700);
DISPLAY 0.617021 (-625 700);
PAINT BLUE (-625 700);
FORCEPROP 2 LAST SEC_TYPE 2626
J 0
(-625 1125);
DISPLAY 1.021277 (-625 1125);
PAINT ORANGE (-625 1125);
DISPLAY INVISIBLE (-625 1125);
FORCEPROP 2 LAST SEC 1
J 0
(-625 1125);
DISPLAY 0.680851 (-625 1125);
PAINT MONO (-625 1125);
DISPLAY INVISIBLE (-625 1125);
FORCEPROP 1 LAST PATH I175
J 0
(-625 1050);
DISPLAY 1.319149 (-625 1050);
PAINT ORANGE (-625 1050);
DISPLAY INVISIBLE (-625 1050);
FORCEPROP 2 LAST ROOM VDDQ_KLM_PWR_VR
J 0
(-625 1050);
DISPLAY 1.361702 (-625 1050);
PAINT ORANGE (-625 1050);
DISPLAY INVISIBLE (-625 1050);
FORCEPROP 2 LAST CDS_LOCATION C1B10
J 0
(-625 1000);
DISPLAY 0.617021 (-625 1000);
PAINT AQUA (-625 1000);
DISPLAY INVISIBLE (-625 1000);
FORCEPROP 2 LAST CDS_LIB mstr_discrete
J 0
(-675 900);
PAINT ORANGE (-675 900);
DISPLAY INVISIBLE (-675 900);
FORCEADD P12V_STBY..1
(-1400 1375);
FORCEPROP 3 LASTPIN (-1400 1325) SIG_NAME P12V_STBY\g
J 0
(-1390 1335);
DISPLAY 0.659574 (-1390 1335);
PAINT MONO (-1390 1335);
DISPLAY INVISIBLE (-1390 1335);
FORCEPROP 1 LAST PATH I182
J 0
(-1355 1377);
DISPLAY 0.340426 (-1355 1377);
PAINT GREEN (-1355 1377);
DISPLAY INVISIBLE (-1355 1377);
FORCEPROP 1 LAST SIZE 1B
J 0
(-1355 1397);
DISPLAY 0.340426 (-1355 1397);
PAINT GREEN (-1355 1397);
DISPLAY INVISIBLE (-1355 1397);
FORCEPROP 2 LAST CDS_LIB mstr_symbols
J 0
(-1400 1375);
PAINT ORANGE (-1400 1375);
DISPLAY INVISIBLE (-1400 1375);
FORCEPROP 1 LAST VOLTAGE 12.0V
J 0
(-1445 1332);
DISPLAY 0.340426 (-1445 1332);
PAINT SKYBLUE (-1445 1332);
DISPLAY INVISIBLE (-1445 1332);
FORCEPROP 1 LAST BODY_TYPE PLUMBING
J 0
(-1445 1332);
DISPLAY 0.340426 (-1445 1332);
PAINT GREEN (-1445 1332);
DISPLAY INVISIBLE (-1445 1332);
FORCEPROP 1 LAST HDL_POWER P12V_STBY
J 0
(-1700 1250);
DISPLAY 0.872340 (-1700 1250);
PAINT ORANGE (-1700 1250);
DISPLAY INVISIBLE (-1700 1250);
FORCEADD GND..1
(-250 2625);
FORCEPROP 3 LASTPIN (-250 2675) SIG_NAME GND\g
J 0
(-240 2685);
DISPLAY 0.659574 (-240 2685);
PAINT MONO (-240 2685);
DISPLAY INVISIBLE (-240 2685);
FORCEPROP 1 LAST PATH I189
J 0
(-175 2625);
DISPLAY 0.872340 (-175 2625);
PAINT AQUA (-175 2625);
DISPLAY INVISIBLE (-175 2625);
FORCEPROP 2 LAST CDS_LIB mstr_symbols
J 0
(-250 2625);
PAINT ORANGE (-250 2625);
DISPLAY INVISIBLE (-250 2625);
FORCEPROP 1 LAST VOLTAGE 0
J 0
(-250 2625);
PAINT SKYBLUE (-250 2625);
DISPLAY INVISIBLE (-250 2625);
FORCEPROP 1 LAST SIZE 1B
J 0
(-175 2575);
DISPLAY 0.893617 (-175 2575);
PAINT GREEN (-175 2575);
DISPLAY INVISIBLE (-175 2575);
FORCEPROP 2 LAST BOM_COST MEM_VRD_PVDDQ_CD
J 0
(-575 2700);
PAINT MONO (-575 2700);
DISPLAY INVISIBLE (-575 2700);
FORCEPROP 2 LAST ROOM VDDQ_ABC_PWR_VR
J 0
(-800 2700);
PAINT ORANGE (-800 2700);
DISPLAY INVISIBLE (-800 2700);
FORCEPROP 1 LAST BODY_TYPE PLUMBING
J 0
(-295 2582);
DISPLAY 0.340426 (-295 2582);
PAINT GREEN (-295 2582);
DISPLAY INVISIBLE (-295 2582);
FORCEPROP 1 LAST HDL_POWER GND
J 0
(-250 2775);
DISPLAY 0.893617 (-250 2775);
PAINT GREEN (-250 2775);
DISPLAY INVISIBLE (-250 2775);
FORCEADD PVDDQ_KLM..1
(-2325 3250);
FORCEPROP 3 LASTPIN (-2325 3200) SIG_NAME PVDDQ_KLM\g
J 0
(-2315 3210);
DISPLAY 0.659574 (-2315 3210);
PAINT MONO (-2315 3210);
DISPLAY INVISIBLE (-2315 3210);
FORCEPROP 2 LAST ROOM VDDQ_KLM_PWR_VR
J 0
(-2100 3350);
PAINT ORANGE (-2100 3350);
DISPLAY INVISIBLE (-2100 3350);
FORCEPROP 2 LAST BOM_COST MEM_VRD_PVPP_AB
J 0
(-2275 3350);
PAINT MONO (-2275 3350);
DISPLAY INVISIBLE (-2275 3350);
FORCEPROP 2 LAST CDS_LIB mstr_symbols
J 0
(-2325 3250);
PAINT ORANGE (-2325 3250);
DISPLAY INVISIBLE (-2325 3250);
FORCEPROP 1 LAST VOLTAGE 1.2V
J 0
(-2370 3207);
DISPLAY 0.340426 (-2370 3207);
PAINT SKYBLUE (-2370 3207);
DISPLAY INVISIBLE (-2370 3207);
FORCEPROP 1 LAST PATH I191
J 0
(-2275 3275);
DISPLAY 0.872340 (-2275 3275);
PAINT AQUA (-2275 3275);
DISPLAY INVISIBLE (-2275 3275);
FORCEPROP 1 LAST BODY_TYPE PLUMBING
J 0
(-2370 3207);
DISPLAY 0.340426 (-2370 3207);
PAINT GREEN (-2370 3207);
DISPLAY INVISIBLE (-2370 3207);
FORCEPROP 1 LAST HDL_POWER PVDDQ_KLM
J 1
(-2325 3300);
DISPLAY 0.872340 (-2325 3300);
PAINT GREEN (-2325 3300);
DISPLAY INVISIBLE (-2325 3300);
FORCEADD PVDDQ_KLM..1
(2550 1000);
FORCEPROP 3 LASTPIN (2550 950) SIG_NAME PVDDQ_KLM\g
J 0
(2560 960);
DISPLAY 0.659574 (2560 960);
PAINT MONO (2560 960);
DISPLAY INVISIBLE (2560 960);
FORCEPROP 2 LAST ROOM VDDQ_KLM_PWR_VR
J 0
(2800 1100);
PAINT ORANGE (2800 1100);
DISPLAY INVISIBLE (2800 1100);
FORCEPROP 1 LAST PATH I195
J 0
(2600 1025);
DISPLAY 0.872340 (2600 1025);
PAINT AQUA (2600 1025);
DISPLAY INVISIBLE (2600 1025);
FORCEPROP 2 LAST BOM_COST MEM_VRD_PVDDQ_CD
J 0
(2625 1100);
PAINT MONO (2625 1100);
DISPLAY INVISIBLE (2625 1100);
FORCEPROP 2 LAST CDS_LIB mstr_symbols
J 0
(2550 1000);
PAINT ORANGE (2550 1000);
DISPLAY INVISIBLE (2550 1000);
FORCEPROP 1 LAST VOLTAGE 1.2V
J 0
(2505 957);
DISPLAY 0.340426 (2505 957);
PAINT SKYBLUE (2505 957);
DISPLAY INVISIBLE (2505 957);
FORCEPROP 1 LAST BODY_TYPE PLUMBING
J 0
(2505 957);
DISPLAY 0.340426 (2505 957);
PAINT GREEN (2505 957);
DISPLAY INVISIBLE (2505 957);
FORCEPROP 1 LAST HDL_POWER PVDDQ_KLM
J 1
(2550 1050);
DISPLAY 0.872340 (2550 1050);
PAINT GREEN (2550 1050);
DISPLAY INVISIBLE (2550 1050);
FORCEADD GND..1
(3300 325);
FORCEPROP 3 LASTPIN (3300 375) SIG_NAME GND\g
J 0
(3310 385);
DISPLAY 0.659574 (3310 385);
PAINT MONO (3310 385);
DISPLAY INVISIBLE (3310 385);
FORCEPROP 1 LAST SIZE 1B
J 0
(3375 275);
DISPLAY 0.893617 (3375 275);
PAINT GREEN (3375 275);
DISPLAY INVISIBLE (3375 275);
FORCEPROP 1 LAST PATH I197
J 0
(3375 325);
DISPLAY 0.872340 (3375 325);
PAINT AQUA (3375 325);
DISPLAY INVISIBLE (3375 325);
FORCEPROP 2 LAST CDS_LIB mstr_symbols
J 0
(3300 325);
PAINT ORANGE (3300 325);
DISPLAY INVISIBLE (3300 325);
FORCEPROP 1 LAST VOLTAGE 0
J 0
(3300 325);
PAINT SKYBLUE (3300 325);
DISPLAY INVISIBLE (3300 325);
FORCEPROP 2 LAST ROOM VDDQ_KLM_PWR_VR
J 0
(2750 400);
PAINT ORANGE (2750 400);
DISPLAY INVISIBLE (2750 400);
FORCEPROP 2 LAST BOM_COST MEM_VRD_PVDDQ_CD
J 0
(2975 400);
PAINT MONO (2975 400);
DISPLAY INVISIBLE (2975 400);
FORCEPROP 1 LAST BODY_TYPE PLUMBING
J 0
(3255 282);
DISPLAY 0.340426 (3255 282);
PAINT GREEN (3255 282);
DISPLAY INVISIBLE (3255 282);
FORCEPROP 1 LAST HDL_POWER GND
J 0
(3300 475);
DISPLAY 0.893617 (3300 475);
PAINT GREEN (3300 475);
DISPLAY INVISIBLE (3300 475);
FORCEADD CAP_A..1
(2550 725);
FORCEPROP 1 LASTPIN (2550 825) $PN 1
J 0
(2560 805);
DISPLAY 0.617021 (2560 805);
PAINT ORANGE (2560 805);
FORCEPROP 1 LAST PACK_TYPE 0603V
J 0
(2600 525);
DISPLAY 0.617021 (2600 525);
PAINT SKYBLUE (2600 525);
FORCEPROP 1 LAST VOLTAGE 4V
J 0
(2600 725);
DISPLAY 0.617021 (2600 725);
PAINT SKYBLUE (2600 725);
FORCEPROP 1 LAST PART_NUMBER 602433-106
J 0
(2600 575);
DISPLAY 0.617021 (2600 575);
PAINT BLUE (2600 575);
FORCEPROP 0 LAST GROUP PWR_MLCC_CAP
J 0
(2606 487);
DISPLAY 0.638298 (2606 487);
PAINT BROWN (2606 487);
DISPLAY BOTH (2606 487);
FORCEPROP 1 LAST TOLERANCE 20%
J 0
(2600 675);
DISPLAY 0.617021 (2600 675);
PAINT SKYBLUE (2600 675);
FORCEPROP 1 LAST MATERIAL X5R
J 0
(2600 625);
DISPLAY 0.617021 (2600 625);
PAINT SKYBLUE (2600 625);
FORCEPROP 1 LAST VALUE 47UF
J 0
(2600 775);
DISPLAY 0.617021 (2600 775);
PAINT SKYBLUE (2600 775);
FORCEPROP 1 LAST LOCATION C8M8
J 0
(2600 825);
DISPLAY 0.617021 (2600 825);
PAINT AQUA (2600 825);
FORCEPROP 1 LASTPIN (2550 625) $PN 2
J 0
(2560 605);
DISPLAY 0.617021 (2560 605);
PAINT ORANGE (2560 605);
FORCEPROP 0 LAST BOM_SS NOPOP
J 0
(2601 421);
DISPLAY 0.638298 (2601 421);
PAINT BROWN (2601 421);
DISPLAY BOTH (2601 421);
FORCEPROP 1 LAST PATH I198
J 0
(2600 875);
DISPLAY 0.978723 (2600 875);
PAINT WHITE (2600 875);
DISPLAY INVISIBLE (2600 875);
FORCEPROP 2 LAST SEC 1
J 0
(2600 925);
DISPLAY 0.680851 (2600 925);
PAINT MONO (2600 925);
DISPLAY INVISIBLE (2600 925);
FORCEPROP 2 LAST SEC_TYPE 0603V
J 0
(2600 925);
DISPLAY 1.021277 (2600 925);
PAINT ORANGE (2600 925);
DISPLAY INVISIBLE (2600 925);
FORCEPROP 2 LAST CDS_SEC 1
J 0
(2600 875);
PAINT ORANGE (2600 875);
DISPLAY INVISIBLE (2600 875);
FORCEPROP 2 LAST CDS_LOCATION C8M8
J 0
(2600 825);
DISPLAY 0.617021 (2600 825);
PAINT AQUA (2600 825);
DISPLAY INVISIBLE (2600 825);
FORCEPROP 2 LAST CDS_LIB dev_discrete
J 0
(2550 725);
PAINT ORANGE (2550 725);
DISPLAY INVISIBLE (2550 725);
FORCEADD CAP_A..1
(2900 725);
FORCEPROP 0 LAST BOM_SS NOPOP
J 0
(2976 371);
DISPLAY 0.638298 (2976 371);
PAINT BROWN (2976 371);
DISPLAY BOTH (2976 371);
FORCEPROP 1 LAST PART_NUMBER 602433-106
J 0
(2950 575);
DISPLAY 0.617021 (2950 575);
PAINT BLUE (2950 575);
FORCEPROP 1 LAST PACK_TYPE 0603V
J 0
(2950 525);
DISPLAY 0.617021 (2950 525);
PAINT SKYBLUE (2950 525);
FORCEPROP 1 LAST TOLERANCE 20%
J 0
(2950 675);
DISPLAY 0.617021 (2950 675);
PAINT SKYBLUE (2950 675);
FORCEPROP 1 LASTPIN (2900 625) $PN 2
J 0
(2910 605);
DISPLAY 0.617021 (2910 605);
PAINT ORANGE (2910 605);
FORCEPROP 1 LASTPIN (2900 825) $PN 1
J 0
(2910 805);
DISPLAY 0.617021 (2910 805);
PAINT ORANGE (2910 805);
FORCEPROP 1 LAST MATERIAL X5R
J 0
(2950 625);
DISPLAY 0.617021 (2950 625);
PAINT SKYBLUE (2950 625);
FORCEPROP 1 LAST VOLTAGE 4V
J 0
(2950 725);
DISPLAY 0.617021 (2950 725);
PAINT SKYBLUE (2950 725);
FORCEPROP 0 LAST GROUP PWR_MLCC_CAP
J 0
(2956 437);
DISPLAY 0.638298 (2956 437);
PAINT BROWN (2956 437);
DISPLAY BOTH (2956 437);
FORCEPROP 1 LAST VALUE 47UF
J 0
(2950 775);
DISPLAY 0.617021 (2950 775);
PAINT SKYBLUE (2950 775);
FORCEPROP 1 LAST LOCATION C2A5
J 0
(2950 825);
DISPLAY 0.617021 (2950 825);
PAINT AQUA (2950 825);
FORCEPROP 2 LAST CDS_LOCATION C2A5
J 0
(2950 825);
DISPLAY 0.617021 (2950 825);
PAINT AQUA (2950 825);
DISPLAY INVISIBLE (2950 825);
FORCEPROP 2 LAST CDS_SEC 1
J 0
(2950 875);
PAINT ORANGE (2950 875);
DISPLAY INVISIBLE (2950 875);
FORCEPROP 2 LAST SEC_TYPE 0603V
J 0
(2950 925);
DISPLAY 1.021277 (2950 925);
PAINT ORANGE (2950 925);
DISPLAY INVISIBLE (2950 925);
FORCEPROP 2 LAST SEC 1
J 0
(2950 925);
DISPLAY 0.680851 (2950 925);
PAINT MONO (2950 925);
DISPLAY INVISIBLE (2950 925);
FORCEPROP 1 LAST PATH I199
J 0
(2950 875);
DISPLAY 0.978723 (2950 875);
PAINT WHITE (2950 875);
DISPLAY INVISIBLE (2950 875);
FORCEPROP 2 LAST CDS_LIB dev_discrete
J 0
(2900 725);
PAINT ORANGE (2900 725);
DISPLAY INVISIBLE (2900 725);
FORCEADD CAP_A..1
(3300 725);
FORCEPROP 1 LAST TOLERANCE 20%
J 0
(3350 675);
DISPLAY 0.617021 (3350 675);
PAINT SKYBLUE (3350 675);
FORCEPROP 1 LAST VALUE 47UF
J 0
(3350 775);
DISPLAY 0.617021 (3350 775);
PAINT SKYBLUE (3350 775);
FORCEPROP 1 LAST LOCATION C2B1
J 0
(3350 825);
DISPLAY 0.617021 (3350 825);
PAINT AQUA (3350 825);
FORCEPROP 1 LASTPIN (3300 625) $PN 2
J 0
(3310 605);
DISPLAY 0.617021 (3310 605);
PAINT ORANGE (3310 605);
FORCEPROP 1 LAST PACK_TYPE 0603V
J 0
(3350 525);
DISPLAY 0.617021 (3350 525);
PAINT SKYBLUE (3350 525);
FORCEPROP 1 LAST PART_NUMBER 602433-106
J 0
(3350 575);
DISPLAY 0.617021 (3350 575);
PAINT BLUE (3350 575);
FORCEPROP 1 LAST MATERIAL X5R
J 0
(3350 625);
DISPLAY 0.617021 (3350 625);
PAINT SKYBLUE (3350 625);
FORCEPROP 1 LAST VOLTAGE 4V
J 0
(3350 725);
DISPLAY 0.617021 (3350 725);
PAINT SKYBLUE (3350 725);
FORCEPROP 1 LASTPIN (3300 825) $PN 1
J 0
(3310 805);
DISPLAY 0.617021 (3310 805);
PAINT ORANGE (3310 805);
FORCEPROP 0 LAST GROUP PWR_MLCC_CAP
J 0
(3356 487);
DISPLAY 0.638298 (3356 487);
PAINT BROWN (3356 487);
DISPLAY BOTH (3356 487);
FORCEPROP 0 LAST BOM_SS NOPOP
J 0
(3376 396);
DISPLAY 0.638298 (3376 396);
PAINT BROWN (3376 396);
DISPLAY BOTH (3376 396);
FORCEPROP 1 LAST PATH I200
J 0
(3350 875);
DISPLAY 0.978723 (3350 875);
PAINT WHITE (3350 875);
DISPLAY INVISIBLE (3350 875);
FORCEPROP 2 LAST SEC 1
J 0
(3350 925);
DISPLAY 0.680851 (3350 925);
PAINT MONO (3350 925);
DISPLAY INVISIBLE (3350 925);
FORCEPROP 2 LAST SEC_TYPE 0603V
J 0
(3350 925);
DISPLAY 1.021277 (3350 925);
PAINT ORANGE (3350 925);
DISPLAY INVISIBLE (3350 925);
FORCEPROP 2 LAST CDS_SEC 1
J 0
(3350 875);
PAINT ORANGE (3350 875);
DISPLAY INVISIBLE (3350 875);
FORCEPROP 2 LAST CDS_LOCATION C2B1
J 0
(3350 825);
DISPLAY 0.617021 (3350 825);
PAINT AQUA (3350 825);
DISPLAY INVISIBLE (3350 825);
FORCEPROP 2 LAST CDS_LIB dev_discrete
J 0
(3300 725);
PAINT ORANGE (3300 725);
DISPLAY INVISIBLE (3300 725);
FORCEADD CAP_A..1
(2525 1425);
FORCEPROP 1 LASTPIN (2525 1325) $PN 2
J 0
(2535 1305);
DISPLAY 0.617021 (2535 1305);
PAINT ORANGE (2535 1305);
FORCEPROP 1 LASTPIN (2525 1525) $PN 1
J 0
(2535 1505);
DISPLAY 0.617021 (2535 1505);
PAINT ORANGE (2535 1505);
FORCEPROP 1 LAST TOLERANCE 20%
J 0
(2575 1375);
DISPLAY 0.617021 (2575 1375);
PAINT SKYBLUE (2575 1375);
FORCEPROP 1 LAST VALUE 47UF
J 0
(2575 1475);
DISPLAY 0.617021 (2575 1475);
PAINT SKYBLUE (2575 1475);
FORCEPROP 1 LAST MATERIAL X5R
J 0
(2575 1325);
DISPLAY 0.617021 (2575 1325);
PAINT SKYBLUE (2575 1325);
FORCEPROP 1 LAST VOLTAGE 4V
J 0
(2575 1425);
DISPLAY 0.617021 (2575 1425);
PAINT SKYBLUE (2575 1425);
FORCEPROP 1 LAST PART_NUMBER 602433-106
J 0
(2575 1275);
DISPLAY 0.617021 (2575 1275);
PAINT BLUE (2575 1275);
FORCEPROP 0 LAST BOM_SS NOPOP
J 0
(2551 1121);
DISPLAY 0.638298 (2551 1121);
PAINT BROWN (2551 1121);
DISPLAY BOTH (2551 1121);
FORCEPROP 1 LAST LOCATION C8L12
J 0
(2575 1525);
DISPLAY 0.617021 (2575 1525);
PAINT AQUA (2575 1525);
FORCEPROP 0 LAST GROUP PWR_MLCC_CAP
J 0
(2581 1187);
DISPLAY 0.638298 (2581 1187);
PAINT BROWN (2581 1187);
DISPLAY BOTH (2581 1187);
FORCEPROP 1 LAST PACK_TYPE 0603V
J 0
(2575 1225);
DISPLAY 0.617021 (2575 1225);
PAINT SKYBLUE (2575 1225);
FORCEPROP 2 LAST CDS_SEC 1
J 0
(2575 1575);
PAINT ORANGE (2575 1575);
DISPLAY INVISIBLE (2575 1575);
FORCEPROP 2 LAST SEC_TYPE 0603V
J 0
(2575 1625);
DISPLAY 1.021277 (2575 1625);
PAINT ORANGE (2575 1625);
DISPLAY INVISIBLE (2575 1625);
FORCEPROP 2 LAST SEC 1
J 0
(2575 1625);
DISPLAY 0.680851 (2575 1625);
PAINT MONO (2575 1625);
DISPLAY INVISIBLE (2575 1625);
FORCEPROP 1 LAST PATH I201
J 0
(2575 1575);
DISPLAY 0.978723 (2575 1575);
PAINT WHITE (2575 1575);
DISPLAY INVISIBLE (2575 1575);
FORCEPROP 2 LAST CDS_LOCATION C8L12
J 0
(2575 1525);
DISPLAY 0.617021 (2575 1525);
PAINT AQUA (2575 1525);
DISPLAY INVISIBLE (2575 1525);
FORCEPROP 2 LAST CDS_LIB dev_discrete
J 0
(2525 1425);
PAINT ORANGE (2525 1425);
DISPLAY INVISIBLE (2525 1425);
FORCEADD CAP_A..1
(2875 1425);
FORCEPROP 1 LAST PACK_TYPE 0603V
J 0
(2925 1225);
DISPLAY 0.617021 (2925 1225);
PAINT SKYBLUE (2925 1225);
FORCEPROP 1 LASTPIN (2875 1325) $PN 2
J 0
(2885 1305);
DISPLAY 0.617021 (2885 1305);
PAINT ORANGE (2885 1305);
FORCEPROP 1 LAST VOLTAGE 4V
J 0
(2925 1425);
DISPLAY 0.617021 (2925 1425);
PAINT SKYBLUE (2925 1425);
FORCEPROP 1 LAST TOLERANCE 20%
J 0
(2925 1375);
DISPLAY 0.617021 (2925 1375);
PAINT SKYBLUE (2925 1375);
FORCEPROP 1 LAST LOCATION C7M5
J 0
(2925 1525);
DISPLAY 0.617021 (2925 1525);
PAINT AQUA (2925 1525);
FORCEPROP 1 LAST MATERIAL X5R
J 0
(2925 1325);
DISPLAY 0.617021 (2925 1325);
PAINT SKYBLUE (2925 1325);
FORCEPROP 1 LASTPIN (2875 1525) $PN 1
J 0
(2885 1505);
DISPLAY 0.617021 (2885 1505);
PAINT ORANGE (2885 1505);
FORCEPROP 1 LAST VALUE 47UF
J 0
(2925 1475);
DISPLAY 0.617021 (2925 1475);
PAINT SKYBLUE (2925 1475);
FORCEPROP 1 LAST PART_NUMBER 602433-106
J 0
(2925 1275);
DISPLAY 0.617021 (2925 1275);
PAINT BLUE (2925 1275);
FORCEPROP 0 LAST BOM_SS NOPOP
J 0
(2926 1071);
DISPLAY 0.638298 (2926 1071);
PAINT BROWN (2926 1071);
DISPLAY BOTH (2926 1071);
FORCEPROP 0 LAST GROUP PWR_MLCC_CAP
J 0
(2906 1112);
DISPLAY 0.638298 (2906 1112);
PAINT BROWN (2906 1112);
DISPLAY BOTH (2906 1112);
FORCEPROP 2 LAST CDS_SEC 1
J 0
(2925 1575);
PAINT ORANGE (2925 1575);
DISPLAY INVISIBLE (2925 1575);
FORCEPROP 2 LAST SEC_TYPE 0603V
J 0
(2925 1625);
DISPLAY 1.021277 (2925 1625);
PAINT ORANGE (2925 1625);
DISPLAY INVISIBLE (2925 1625);
FORCEPROP 2 LAST SEC 1
J 0
(2925 1625);
DISPLAY 0.680851 (2925 1625);
PAINT MONO (2925 1625);
DISPLAY INVISIBLE (2925 1625);
FORCEPROP 1 LAST PATH I202
J 0
(2925 1575);
DISPLAY 0.978723 (2925 1575);
PAINT WHITE (2925 1575);
DISPLAY INVISIBLE (2925 1575);
FORCEPROP 2 LAST CDS_LOCATION C7M5
J 0
(2925 1525);
DISPLAY 0.617021 (2925 1525);
PAINT AQUA (2925 1525);
DISPLAY INVISIBLE (2925 1525);
FORCEPROP 2 LAST CDS_LIB dev_discrete
J 0
(2875 1425);
PAINT ORANGE (2875 1425);
DISPLAY INVISIBLE (2875 1425);
FORCEADD CAP_A..1
(3275 1425);
FORCEPROP 1 LAST PART_NUMBER 602433-106
J 0
(3325 1275);
DISPLAY 0.617021 (3325 1275);
PAINT BLUE (3325 1275);
FORCEPROP 1 LAST PACK_TYPE 0603V
J 0
(3325 1225);
DISPLAY 0.617021 (3325 1225);
PAINT SKYBLUE (3325 1225);
FORCEPROP 0 LAST GROUP PWR_MLCC_CAP
J 0
(3331 1187);
DISPLAY 0.638298 (3331 1187);
PAINT BROWN (3331 1187);
DISPLAY BOTH (3331 1187);
FORCEPROP 0 LAST BOM_SS 078.1061T.M001
J 0
(3326 1071);
DISPLAY 0.638298 (3326 1071);
PAINT BROWN (3326 1071);
DISPLAY BOTH (3326 1071);
FORCEPROP 1 LASTPIN (3275 1525) $PN 1
J 0
(3285 1505);
DISPLAY 0.617021 (3285 1505);
PAINT ORANGE (3285 1505);
FORCEPROP 1 LAST MATERIAL X5R
J 0
(3325 1325);
DISPLAY 0.617021 (3325 1325);
PAINT SKYBLUE (3325 1325);
FORCEPROP 1 LAST TOLERANCE 20%
J 0
(3325 1375);
DISPLAY 0.617021 (3325 1375);
PAINT SKYBLUE (3325 1375);
FORCEPROP 1 LASTPIN (3275 1325) $PN 2
J 0
(3285 1305);
DISPLAY 0.617021 (3285 1305);
PAINT ORANGE (3285 1305);
FORCEPROP 1 LAST VOLTAGE 4V
J 0
(3325 1425);
DISPLAY 0.617021 (3325 1425);
PAINT SKYBLUE (3325 1425);
FORCEPROP 1 LAST VALUE 47UF
J 0
(3325 1475);
DISPLAY 0.617021 (3325 1475);
PAINT SKYBLUE (3325 1475);
FORCEPROP 1 LAST LOCATION C8M10
J 0
(3325 1525);
DISPLAY 0.617021 (3325 1525);
PAINT AQUA (3325 1525);
FORCEPROP 1 LAST PATH I203
J 0
(3325 1575);
DISPLAY 0.978723 (3325 1575);
PAINT WHITE (3325 1575);
DISPLAY INVISIBLE (3325 1575);
FORCEPROP 2 LAST SEC 1
J 0
(3325 1625);
DISPLAY 0.680851 (3325 1625);
PAINT MONO (3325 1625);
DISPLAY INVISIBLE (3325 1625);
FORCEPROP 2 LAST SEC_TYPE 0603V
J 0
(3325 1625);
DISPLAY 1.021277 (3325 1625);
PAINT ORANGE (3325 1625);
DISPLAY INVISIBLE (3325 1625);
FORCEPROP 2 LAST CDS_SEC 1
J 0
(3325 1575);
PAINT ORANGE (3325 1575);
DISPLAY INVISIBLE (3325 1575);
FORCEPROP 2 LAST CDS_LOCATION C8M10
J 0
(3325 1525);
DISPLAY 0.617021 (3325 1525);
PAINT AQUA (3325 1525);
DISPLAY INVISIBLE (3325 1525);
FORCEPROP 2 LAST CDS_LIB dev_discrete
J 0
(3275 1425);
PAINT ORANGE (3275 1425);
DISPLAY INVISIBLE (3275 1425);
FORCEADD CAP_A..1
(3625 1425);
FORCEPROP 1 LAST PACK_TYPE 0603V
J 0
(3675 1225);
DISPLAY 0.617021 (3675 1225);
PAINT SKYBLUE (3675 1225);
FORCEPROP 1 LASTPIN (3625 1325) $PN 2
J 0
(3635 1305);
DISPLAY 0.617021 (3635 1305);
PAINT ORANGE (3635 1305);
FORCEPROP 1 LAST VOLTAGE 4V
J 0
(3675 1425);
DISPLAY 0.617021 (3675 1425);
PAINT SKYBLUE (3675 1425);
FORCEPROP 1 LAST VALUE 47UF
J 0
(3675 1475);
DISPLAY 0.617021 (3675 1475);
PAINT SKYBLUE (3675 1475);
FORCEPROP 1 LASTPIN (3625 1525) $PN 1
J 0
(3635 1505);
DISPLAY 0.617021 (3635 1505);
PAINT ORANGE (3635 1505);
FORCEPROP 1 LAST LOCATION C2B2
J 0
(3675 1525);
DISPLAY 0.617021 (3675 1525);
PAINT AQUA (3675 1525);
FORCEPROP 1 LAST TOLERANCE 20%
J 0
(3675 1375);
DISPLAY 0.617021 (3675 1375);
PAINT SKYBLUE (3675 1375);
FORCEPROP 1 LAST MATERIAL X5R
J 0
(3675 1325);
DISPLAY 0.617021 (3675 1325);
PAINT SKYBLUE (3675 1325);
FORCEPROP 1 LAST PART_NUMBER 602433-106
J 0
(3675 1275);
DISPLAY 0.617021 (3675 1275);
PAINT BLUE (3675 1275);
FORCEPROP 0 LAST BOM_SS NOPOP
J 0
(3701 1046);
DISPLAY 0.638298 (3701 1046);
PAINT BROWN (3701 1046);
DISPLAY BOTH (3701 1046);
FORCEPROP 0 LAST GROUP PWR_MLCC_CAP
J 0
(3681 1112);
DISPLAY 0.638298 (3681 1112);
PAINT BROWN (3681 1112);
DISPLAY BOTH (3681 1112);
FORCEPROP 2 LAST CDS_SEC 1
J 0
(3675 1575);
PAINT ORANGE (3675 1575);
DISPLAY INVISIBLE (3675 1575);
FORCEPROP 2 LAST SEC_TYPE 0603V
J 0
(3675 1625);
DISPLAY 1.021277 (3675 1625);
PAINT ORANGE (3675 1625);
DISPLAY INVISIBLE (3675 1625);
FORCEPROP 2 LAST SEC 1
J 0
(3675 1625);
DISPLAY 0.680851 (3675 1625);
PAINT MONO (3675 1625);
DISPLAY INVISIBLE (3675 1625);
FORCEPROP 1 LAST PATH I204
J 0
(3675 1575);
DISPLAY 0.978723 (3675 1575);
PAINT WHITE (3675 1575);
DISPLAY INVISIBLE (3675 1575);
FORCEPROP 2 LAST CDS_LOCATION C2B2
J 0
(3675 1525);
DISPLAY 0.617021 (3675 1525);
PAINT AQUA (3675 1525);
DISPLAY INVISIBLE (3675 1525);
FORCEPROP 2 LAST CDS_LIB dev_discrete
J 0
(3625 1425);
PAINT ORANGE (3625 1425);
DISPLAY INVISIBLE (3625 1425);
FORCEADD CAP_A..1
(3975 1425);
FORCEPROP 1 LASTPIN (3975 1525) $PN 1
J 0
(3985 1505);
DISPLAY 0.617021 (3985 1505);
PAINT ORANGE (3985 1505);
FORCEPROP 1 LAST LOCATION C8M9
J 0
(4025 1525);
DISPLAY 0.617021 (4025 1525);
PAINT AQUA (4025 1525);
FORCEPROP 1 LAST TOLERANCE 20%
J 0
(4025 1375);
DISPLAY 0.617021 (4025 1375);
PAINT SKYBLUE (4025 1375);
FORCEPROP 1 LAST VALUE 47UF
J 0
(4025 1475);
DISPLAY 0.617021 (4025 1475);
PAINT SKYBLUE (4025 1475);
FORCEPROP 1 LAST VOLTAGE 4V
J 0
(4025 1425);
DISPLAY 0.617021 (4025 1425);
PAINT SKYBLUE (4025 1425);
FORCEPROP 1 LAST MATERIAL X5R
J 0
(4025 1325);
DISPLAY 0.617021 (4025 1325);
PAINT SKYBLUE (4025 1325);
FORCEPROP 1 LASTPIN (3975 1325) $PN 2
J 0
(3985 1305);
DISPLAY 0.617021 (3985 1305);
PAINT ORANGE (3985 1305);
FORCEPROP 0 LAST BOM_SS NOPOP
J 0
(4051 1071);
DISPLAY 0.638298 (4051 1071);
PAINT BROWN (4051 1071);
DISPLAY BOTH (4051 1071);
FORCEPROP 0 LAST GROUP PWR_MLCC_CAP
J 0
(4031 1187);
DISPLAY 0.638298 (4031 1187);
PAINT BROWN (4031 1187);
DISPLAY BOTH (4031 1187);
FORCEPROP 1 LAST PACK_TYPE 0603V
J 0
(4025 1225);
DISPLAY 0.617021 (4025 1225);
PAINT SKYBLUE (4025 1225);
FORCEPROP 1 LAST PART_NUMBER 602433-106
J 0
(4025 1275);
DISPLAY 0.617021 (4025 1275);
PAINT BLUE (4025 1275);
FORCEPROP 2 LAST CDS_SEC 1
J 0
(4025 1575);
PAINT ORANGE (4025 1575);
DISPLAY INVISIBLE (4025 1575);
FORCEPROP 2 LAST SEC_TYPE 0603V
J 0
(4025 1625);
DISPLAY 1.021277 (4025 1625);
PAINT ORANGE (4025 1625);
DISPLAY INVISIBLE (4025 1625);
FORCEPROP 2 LAST SEC 1
J 0
(4025 1625);
DISPLAY 0.680851 (4025 1625);
PAINT MONO (4025 1625);
DISPLAY INVISIBLE (4025 1625);
FORCEPROP 1 LAST PATH I205
J 0
(4025 1575);
DISPLAY 0.978723 (4025 1575);
PAINT WHITE (4025 1575);
DISPLAY INVISIBLE (4025 1575);
FORCEPROP 2 LAST CDS_LOCATION C8M9
J 0
(4025 1525);
DISPLAY 0.617021 (4025 1525);
PAINT AQUA (4025 1525);
DISPLAY INVISIBLE (4025 1525);
FORCEPROP 2 LAST CDS_LIB dev_discrete
J 0
(3975 1425);
PAINT ORANGE (3975 1425);
DISPLAY INVISIBLE (3975 1425);
FORCEADD CAP_A..1
(4375 1425);
FORCEPROP 0 LAST BOM_SS NOPOP
J 0
(4451 1071);
DISPLAY 0.638298 (4451 1071);
PAINT BROWN (4451 1071);
DISPLAY BOTH (4451 1071);
FORCEPROP 0 LAST GROUP PWR_MLCC_CAP
J 0
(4431 1112);
DISPLAY 0.638298 (4431 1112);
PAINT BROWN (4431 1112);
DISPLAY BOTH (4431 1112);
FORCEPROP 1 LAST PACK_TYPE 0603V
J 0
(4425 1225);
DISPLAY 0.617021 (4425 1225);
PAINT SKYBLUE (4425 1225);
FORCEPROP 1 LASTPIN (4375 1325) $PN 2
J 0
(4385 1305);
DISPLAY 0.617021 (4385 1305);
PAINT ORANGE (4385 1305);
FORCEPROP 1 LASTPIN (4375 1525) $PN 1
J 0
(4385 1505);
DISPLAY 0.617021 (4385 1505);
PAINT ORANGE (4385 1505);
FORCEPROP 1 LAST MATERIAL X5R
J 0
(4425 1325);
DISPLAY 0.617021 (4425 1325);
PAINT SKYBLUE (4425 1325);
FORCEPROP 1 LAST VOLTAGE 4V
J 0
(4425 1425);
DISPLAY 0.617021 (4425 1425);
PAINT SKYBLUE (4425 1425);
FORCEPROP 1 LAST TOLERANCE 20%
J 0
(4425 1375);
DISPLAY 0.617021 (4425 1375);
PAINT SKYBLUE (4425 1375);
FORCEPROP 1 LAST LOCATION C8M2
J 0
(4425 1525);
DISPLAY 0.617021 (4425 1525);
PAINT AQUA (4425 1525);
FORCEPROP 1 LAST VALUE 47UF
J 0
(4425 1475);
DISPLAY 0.617021 (4425 1475);
PAINT SKYBLUE (4425 1475);
FORCEPROP 1 LAST PART_NUMBER 602433-106
J 0
(4425 1275);
DISPLAY 0.617021 (4425 1275);
PAINT BLUE (4425 1275);
FORCEPROP 1 LAST PATH I206
J 0
(4425 1575);
DISPLAY 0.978723 (4425 1575);
PAINT WHITE (4425 1575);
DISPLAY INVISIBLE (4425 1575);
FORCEPROP 2 LAST SEC 1
J 0
(4425 1625);
DISPLAY 0.680851 (4425 1625);
PAINT MONO (4425 1625);
DISPLAY INVISIBLE (4425 1625);
FORCEPROP 2 LAST SEC_TYPE 0603V
J 0
(4425 1625);
DISPLAY 1.021277 (4425 1625);
PAINT ORANGE (4425 1625);
DISPLAY INVISIBLE (4425 1625);
FORCEPROP 2 LAST CDS_SEC 1
J 0
(4425 1575);
PAINT ORANGE (4425 1575);
DISPLAY INVISIBLE (4425 1575);
FORCEPROP 2 LAST CDS_LOCATION C8M2
J 0
(4425 1525);
DISPLAY 0.617021 (4425 1525);
PAINT AQUA (4425 1525);
DISPLAY INVISIBLE (4425 1525);
FORCEPROP 2 LAST CDS_LIB dev_discrete
J 0
(4375 1425);
PAINT ORANGE (4375 1425);
DISPLAY INVISIBLE (4375 1425);
FORCEADD PVDDQ_KLM..1
(-1300 3250);
FORCEPROP 3 LASTPIN (-1300 3200) SIG_NAME PVDDQ_KLM\g
J 0
(-1290 3210);
DISPLAY 0.659574 (-1290 3210);
PAINT MONO (-1290 3210);
DISPLAY INVISIBLE (-1290 3210);
FORCEPROP 2 LAST CDS_LIB mstr_symbols
J 0
(-1300 3250);
PAINT ORANGE (-1300 3250);
DISPLAY INVISIBLE (-1300 3250);
FORCEPROP 1 LAST VOLTAGE 1.2V
J 0
(-1345 3207);
DISPLAY 0.340426 (-1345 3207);
PAINT SKYBLUE (-1345 3207);
DISPLAY INVISIBLE (-1345 3207);
FORCEPROP 2 LAST ROOM VDDQ_KLM_PWR_VR
J 0
(-1075 3350);
PAINT ORANGE (-1075 3350);
DISPLAY INVISIBLE (-1075 3350);
FORCEPROP 1 LAST PATH I207
J 0
(-1250 3275);
DISPLAY 0.872340 (-1250 3275);
PAINT AQUA (-1250 3275);
DISPLAY INVISIBLE (-1250 3275);
FORCEPROP 2 LAST BOM_COST MEM_VRD_PVPP_AB
J 0
(-1250 3350);
PAINT MONO (-1250 3350);
DISPLAY INVISIBLE (-1250 3350);
FORCEPROP 1 LAST BODY_TYPE PLUMBING
J 0
(-1345 3207);
DISPLAY 0.340426 (-1345 3207);
PAINT GREEN (-1345 3207);
DISPLAY INVISIBLE (-1345 3207);
FORCEPROP 1 LAST HDL_POWER PVDDQ_KLM
J 1
(-1300 3300);
DISPLAY 0.872340 (-1300 3300);
PAINT GREEN (-1300 3300);
DISPLAY INVISIBLE (-1300 3300);
FORCEADD GND..1
(-2325 2475);
FORCEPROP 3 LASTPIN (-2325 2525) SIG_NAME GND\g
J 0
(-2315 2535);
DISPLAY 0.659574 (-2315 2535);
PAINT MONO (-2315 2535);
DISPLAY INVISIBLE (-2315 2535);
FORCEPROP 1 LAST HDL_POWER GND
J 0
(-2325 2625);
DISPLAY 0.893617 (-2325 2625);
PAINT GREEN (-2325 2625);
DISPLAY INVISIBLE (-2325 2625);
FORCEPROP 1 LAST BODY_TYPE PLUMBING
J 0
(-2370 2432);
DISPLAY 0.340426 (-2370 2432);
PAINT GREEN (-2370 2432);
DISPLAY INVISIBLE (-2370 2432);
FORCEPROP 1 LAST PATH I208
J 0
(-2250 2475);
DISPLAY 0.872340 (-2250 2475);
PAINT AQUA (-2250 2475);
DISPLAY INVISIBLE (-2250 2475);
FORCEPROP 2 LAST CDS_LIB mstr_symbols
J 0
(-2325 2475);
PAINT ORANGE (-2325 2475);
DISPLAY INVISIBLE (-2325 2475);
FORCEPROP 1 LAST VOLTAGE 0
J 0
(-2325 2475);
PAINT SKYBLUE (-2325 2475);
DISPLAY INVISIBLE (-2325 2475);
FORCEPROP 1 LAST SIZE 1B
J 0
(-2250 2425);
DISPLAY 0.893617 (-2250 2425);
PAINT GREEN (-2250 2425);
DISPLAY INVISIBLE (-2250 2425);
FORCEPROP 2 LAST BOM_COST MEM_VRD_PVDDQ_CD
J 0
(-2650 2550);
PAINT MONO (-2650 2550);
DISPLAY INVISIBLE (-2650 2550);
FORCEPROP 2 LAST ROOM VDDQ_ABC_PWR_VR
J 0
(-2875 2550);
PAINT ORANGE (-2875 2550);
DISPLAY INVISIBLE (-2875 2550);
FORCEADD PVDDQ_KLM..1
(-2250 175);
FORCEPROP 3 LASTPIN (-2250 125) SIG_NAME PVDDQ_KLM\g
J 0
(-2240 135);
DISPLAY 0.659574 (-2240 135);
PAINT MONO (-2240 135);
DISPLAY INVISIBLE (-2240 135);
FORCEPROP 2 LAST ROOM VDDQ_KLM_PWR_VR
J 0
(-2250 275);
DISPLAY 1.936170 (-2250 275);
PAINT ORANGE (-2250 275);
DISPLAY INVISIBLE (-2250 275);
FORCEPROP 2 LAST BOM_COST VDDQ_KLM_PWR_VR
J 0
(-2250 275);
DISPLAY 1.446809 (-2250 275);
PAINT MONO (-2250 275);
DISPLAY INVISIBLE (-2250 275);
FORCEPROP 1 LAST PATH I224
J 0
(-2200 200);
DISPLAY 0.872340 (-2200 200);
PAINT AQUA (-2200 200);
DISPLAY INVISIBLE (-2200 200);
FORCEPROP 1 LAST VOLTAGE 1.2V
J 0
(-2295 132);
DISPLAY 0.340426 (-2295 132);
PAINT SKYBLUE (-2295 132);
DISPLAY INVISIBLE (-2295 132);
FORCEPROP 2 LAST CDS_LIB mstr_symbols
J 0
(-2250 175);
PAINT ORANGE (-2250 175);
DISPLAY INVISIBLE (-2250 175);
FORCEPROP 1 LAST BODY_TYPE PLUMBING
J 0
(-2295 132);
DISPLAY 0.340426 (-2295 132);
PAINT GREEN (-2295 132);
DISPLAY INVISIBLE (-2295 132);
FORCEPROP 1 LAST HDL_POWER PVDDQ_KLM
J 1
(-2250 225);
DISPLAY 0.872340 (-2250 225);
PAINT GREEN (-2250 225);
DISPLAY INVISIBLE (-2250 225);
FORCEADD GND..1
(-2250 -400);
FORCEPROP 3 LASTPIN (-2250 -350) SIG_NAME GND\g
J 0
(-2240 -340);
DISPLAY 0.659574 (-2240 -340);
PAINT MONO (-2240 -340);
DISPLAY INVISIBLE (-2240 -340);
FORCEPROP 2 LAST BOM_COST PROC_VRD_VCCIN_CPU0
J 0
(-2625 -325);
DISPLAY 1.446809 (-2625 -325);
PAINT MONO (-2625 -325);
DISPLAY INVISIBLE (-2625 -325);
FORCEPROP 2 LAST ROOM VDDQ_ABC_PWR_VR
J 0
(-2800 -325);
DISPLAY 1.936170 (-2800 -325);
PAINT ORANGE (-2800 -325);
DISPLAY INVISIBLE (-2800 -325);
FORCEPROP 2 LAST CDS_LIB mstr_symbols
J 0
(-2250 -400);
PAINT ORANGE (-2250 -400);
DISPLAY INVISIBLE (-2250 -400);
FORCEPROP 1 LAST VOLTAGE 0
J 0
(-2250 -400);
PAINT SKYBLUE (-2250 -400);
DISPLAY INVISIBLE (-2250 -400);
FORCEPROP 1 LAST PATH I226
J 0
(-2175 -400);
DISPLAY 0.872340 (-2175 -400);
PAINT AQUA (-2175 -400);
DISPLAY INVISIBLE (-2175 -400);
FORCEPROP 1 LAST SIZE 1B
J 0
(-2175 -450);
DISPLAY 1.723404 (-2175 -450);
PAINT GREEN (-2175 -450);
DISPLAY INVISIBLE (-2175 -450);
FORCEPROP 1 LAST BODY_TYPE PLUMBING
J 0
(-2295 -443);
DISPLAY 0.340426 (-2295 -443);
PAINT GREEN (-2295 -443);
DISPLAY INVISIBLE (-2295 -443);
FORCEPROP 1 LAST HDL_POWER GND
J 0
(-2250 -250);
DISPLAY 1.723404 (-2250 -250);
PAINT GREEN (-2250 -250);
DISPLAY INVISIBLE (-2250 -250);
FORCEADD PVDDQ_KLM..1
(-2225 -525);
FORCEPROP 3 LASTPIN (-2225 -575) SIG_NAME PVDDQ_KLM\g
J 0
(-2215 -565);
DISPLAY 0.659574 (-2215 -565);
PAINT MONO (-2215 -565);
DISPLAY INVISIBLE (-2215 -565);
FORCEPROP 1 LAST PATH I242
J 0
(-2175 -500);
DISPLAY 0.872340 (-2175 -500);
PAINT AQUA (-2175 -500);
DISPLAY INVISIBLE (-2175 -500);
FORCEPROP 2 LAST BOM_COST VDDQ_KLM_PWR_VR
J 0
(-2225 -425);
DISPLAY 1.446809 (-2225 -425);
PAINT MONO (-2225 -425);
DISPLAY INVISIBLE (-2225 -425);
FORCEPROP 2 LAST ROOM VDDQ_KLM_PWR_VR
J 0
(-2225 -425);
DISPLAY 1.936170 (-2225 -425);
PAINT ORANGE (-2225 -425);
DISPLAY INVISIBLE (-2225 -425);
FORCEPROP 2 LAST CDS_LIB mstr_symbols
J 0
(-2225 -525);
PAINT ORANGE (-2225 -525);
DISPLAY INVISIBLE (-2225 -525);
FORCEPROP 1 LAST VOLTAGE 1.2V
J 0
(-2270 -568);
DISPLAY 0.340426 (-2270 -568);
PAINT SKYBLUE (-2270 -568);
DISPLAY INVISIBLE (-2270 -568);
FORCEPROP 1 LAST BODY_TYPE PLUMBING
J 0
(-2270 -568);
DISPLAY 0.340426 (-2270 -568);
PAINT GREEN (-2270 -568);
DISPLAY INVISIBLE (-2270 -568);
FORCEPROP 1 LAST HDL_POWER PVDDQ_KLM
J 1
(-2225 -475);
DISPLAY 0.872340 (-2225 -475);
PAINT GREEN (-2225 -475);
DISPLAY INVISIBLE (-2225 -475);
FORCEADD GND..1
(-2225 -1075);
FORCEPROP 3 LASTPIN (-2225 -1025) SIG_NAME GND\g
J 0
(-2215 -1015);
DISPLAY 0.659574 (-2215 -1015);
PAINT MONO (-2215 -1015);
DISPLAY INVISIBLE (-2215 -1015);
FORCEPROP 1 LAST SIZE 1B
J 0
(-2150 -1125);
DISPLAY 1.723404 (-2150 -1125);
PAINT GREEN (-2150 -1125);
DISPLAY INVISIBLE (-2150 -1125);
FORCEPROP 1 LAST VOLTAGE 0
J 0
(-2225 -1075);
PAINT SKYBLUE (-2225 -1075);
DISPLAY INVISIBLE (-2225 -1075);
FORCEPROP 2 LAST CDS_LIB mstr_symbols
J 0
(-2225 -1075);
PAINT ORANGE (-2225 -1075);
DISPLAY INVISIBLE (-2225 -1075);
FORCEPROP 1 LAST PATH I244
J 0
(-2150 -1075);
DISPLAY 0.872340 (-2150 -1075);
PAINT AQUA (-2150 -1075);
DISPLAY INVISIBLE (-2150 -1075);
FORCEPROP 2 LAST BOM_COST PROC_VRD_VCCIN_CPU0
J 0
(-2600 -1000);
DISPLAY 1.446809 (-2600 -1000);
PAINT MONO (-2600 -1000);
DISPLAY INVISIBLE (-2600 -1000);
FORCEPROP 2 LAST ROOM VDDQ_ABC_PWR_VR
J 0
(-2775 -1000);
DISPLAY 1.936170 (-2775 -1000);
PAINT ORANGE (-2775 -1000);
DISPLAY INVISIBLE (-2775 -1000);
FORCEPROP 1 LAST BODY_TYPE PLUMBING
J 0
(-2270 -1118);
DISPLAY 0.340426 (-2270 -1118);
PAINT GREEN (-2270 -1118);
DISPLAY INVISIBLE (-2270 -1118);
FORCEPROP 1 LAST HDL_POWER GND
J 0
(-2225 -925);
DISPLAY 1.723404 (-2225 -925);
PAINT GREEN (-2225 -925);
DISPLAY INVISIBLE (-2225 -925);
FORCEADD SHUNT..1
(75 2175);
FORCEPROP 1 LASTPIN (-75 2175) $PN 1
J 2
(-25 2185);
DISPLAY 0.617021 (-25 2185);
PAINT ORANGE (-25 2185);
FORCEPROP 1 LAST PART_NUMBER N_A
J 0
(0 2085);
DISPLAY 0.617021 (0 2085);
PAINT BLUE (0 2085);
FORCEPROP 1 LASTPIN (225 2175) $PN 2
J 0
(185 2185);
DISPLAY 0.617021 (185 2185);
PAINT ORANGE (185 2185);
FORCEPROP 1 LAST LOCATION SH7L2
J 0
(0 2225);
DISPLAY 0.617021 (0 2225);
PAINT AQUA (0 2225);
FORCEPROP 2 LAST SEC_TYPE SH0201
J 0
(25 2325);
DISPLAY 1.021277 (25 2325);
PAINT ORANGE (25 2325);
DISPLAY INVISIBLE (25 2325);
FORCEPROP 1 LAST PATH I245
J 0
(25 2275);
DISPLAY 0.978723 (25 2275);
PAINT ORANGE (25 2275);
DISPLAY INVISIBLE (25 2275);
FORCEPROP 2 LAST CDS_LIB mstr_misc
J 0
(75 2175);
PAINT ORANGE (75 2175);
DISPLAY INVISIBLE (75 2175);
FORCEPROP 1 LAST PACK_TYPE SH0201
J 0
(15 1990);
DISPLAY 0.978723 (15 1990);
PAINT SKYBLUE (15 1990);
DISPLAY INVISIBLE (15 1990);
FORCEPROP 1 LAST PIN_SHORT A:B
J 0
(0 1925);
DISPLAY 1.021277 (0 1925);
PAINT ORANGE (0 1925);
DISPLAY INVISIBLE (0 1925);
FORCEPROP 0 LAST SEC 1
J 0
(0 2275);
DISPLAY 0.680851 (0 2275);
PAINT MONO (0 2275);
DISPLAY INVISIBLE (0 2275);
FORCEPROP 1 LAST MATERIAL EMPTY
J 0
(0 2040);
DISPLAY 0.978723 (0 2040);
PAINT RED (0 2040);
DISPLAY INVISIBLE (0 2040);
FORCEADD SHUNT..1
(75 1725);
FORCEPROP 1 LASTPIN (-75 1725) $PN 1
J 2
(-25 1735);
DISPLAY 0.617021 (-25 1735);
PAINT ORANGE (-25 1735);
FORCEPROP 1 LAST PART_NUMBER N_A
J 0
(0 1635);
DISPLAY 0.617021 (0 1635);
PAINT BLUE (0 1635);
FORCEPROP 1 LAST LOCATION SH7L1
J 0
(0 1775);
DISPLAY 0.617021 (0 1775);
PAINT AQUA (0 1775);
FORCEPROP 1 LASTPIN (225 1725) $PN 2
J 0
(185 1735);
DISPLAY 0.617021 (185 1735);
PAINT ORANGE (185 1735);
FORCEPROP 1 LAST PATH I246
J 0
(25 1825);
DISPLAY 0.978723 (25 1825);
PAINT ORANGE (25 1825);
DISPLAY INVISIBLE (25 1825);
FORCEPROP 2 LAST SEC_TYPE SH0201
J 0
(25 1875);
DISPLAY 1.021277 (25 1875);
PAINT ORANGE (25 1875);
DISPLAY INVISIBLE (25 1875);
FORCEPROP 2 LAST CDS_LIB mstr_misc
J 0
(75 1725);
PAINT ORANGE (75 1725);
DISPLAY INVISIBLE (75 1725);
FORCEPROP 1 LAST PACK_TYPE SH0201
J 0
(15 1540);
DISPLAY 0.978723 (15 1540);
PAINT SKYBLUE (15 1540);
DISPLAY INVISIBLE (15 1540);
FORCEPROP 1 LAST PIN_SHORT A:B
J 0
(0 1475);
DISPLAY 1.021277 (0 1475);
PAINT ORANGE (0 1475);
DISPLAY INVISIBLE (0 1475);
FORCEPROP 0 LAST SEC 1
J 0
(0 1825);
DISPLAY 0.680851 (0 1825);
PAINT MONO (0 1825);
DISPLAY INVISIBLE (0 1825);
FORCEPROP 1 LAST MATERIAL EMPTY
J 0
(0 1590);
DISPLAY 0.978723 (0 1590);
PAINT RED (0 1590);
DISPLAY INVISIBLE (0 1590);
FORCEADD IND-100NH-35-GP..1
R 1
(-1050 1125);
FORCEPROP 2 LAST TYPE IRMS=29A@DELTA_T<45C
J 0
(-1200 900);
DISPLAY 0.638298 (-1200 900);
PAINT GREEN (-1200 900);
FORCEPROP 2 LAST PACK_SIZE DCR=0.16MOHM
J 0
(-1200 850);
DISPLAY 0.638298 (-1200 850);
PAINT GREEN (-1200 850);
FORCEPROP 2 LAST RATED ISAT=16A@25C
J 0
(-1200 950);
DISPLAY 0.638298 (-1200 950);
PAINT GREEN (-1200 950);
FORCEPROP 2 LAST ATTRIBUTE 100NH
J 0
(-1200 1000);
DISPLAY 0.638298 (-1200 1000);
PAINT GREEN (-1200 1000);
FORCEPROP 2 LASTPIN (-1200 1100) $PN 1
J 2
(-1210 1110);
DISPLAY 0.808511 (-1210 1110);
PAINT ORANGE (-1210 1110);
FORCEPROP 1 LAST LOCATION L1B1
J 0
(-1175 1175);
DISPLAY 0.617021 (-1175 1175);
PAINT GREEN (-1175 1175);
FORCEPROP 2 LASTPIN (-900 1100) $PN 2
J 0
(-890 1110);
DISPLAY 0.808511 (-890 1110);
PAINT ORANGE (-890 1110);
FORCEPROP 1 LAST VALUE IND-100NH-35-GP
J 0
(-1200 1050);
DISPLAY 0.617021 (-1200 1050);
PAINT GREEN (-1200 1050);
FORCEPROP 1 LAST PATH I247
R 1
J 0
(-1050 1125);
DISPLAY 0.617021 (-1050 1125);
PAINT GREEN (-1050 1125);
DISPLAY INVISIBLE (-1050 1125);
FORCEPROP 1 LAST PACK_TYPE DISCRET-G8
R 1
J 0
(-1050 1125);
DISPLAY 0.617021 (-1050 1125);
PAINT GREEN (-1050 1125);
DISPLAY INVISIBLE (-1050 1125);
FORCEPROP 2 LAST SEC 1
J 0
(-1200 1100);
DISPLAY 0.680851 (-1200 1100);
PAINT MONO (-1200 1100);
DISPLAY INVISIBLE (-1200 1100);
FORCEPROP 2 LAST SEC_TYPE DISCRET-G8
J 0
(-1200 1100);
DISPLAY 1.021277 (-1200 1100);
PAINT ORANGE (-1200 1100);
DISPLAY INVISIBLE (-1200 1100);
FORCEPROP 1 LAST PART_NUMBER 068.1011N.M001
R 1
J 0
(-1050 1125);
DISPLAY 0.617021 (-1050 1125);
PAINT GREEN (-1050 1125);
DISPLAY INVISIBLE (-1050 1125);
FORCEPROP 2 LAST CDS_LIB w_hdl
R 1
J 0
(-1050 1125);
PAINT MONO (-1050 1125);
DISPLAY INVISIBLE (-1050 1125);
FORCEPROP 1 LAST CDS_LMAN_SYM_OUTLINE -75,100,75,-100
R 1
J 0
(-1050 1125);
DISPLAY 0.468085 (-1050 1125);
PAINT GREEN (-1050 1125);
DISPLAY INVISIBLE (-1050 1125);
FORCEADD PVDDQ_KLM..1
(650 3100);
FORCEPROP 3 LASTPIN (650 3050) SIG_NAME PVDDQ_KLM\g
J 0
(660 3060);
DISPLAY 0.659574 (660 3060);
PAINT MONO (660 3060);
DISPLAY INVISIBLE (660 3060);
FORCEPROP 1 LAST HDL_POWER PVDDQ_KLM
J 1
(650 3150);
DISPLAY 0.872340 (650 3150);
PAINT GREEN (650 3150);
DISPLAY INVISIBLE (650 3150);
FORCEPROP 1 LAST BODY_TYPE PLUMBING
J 0
(605 3057);
DISPLAY 0.340426 (605 3057);
PAINT GREEN (605 3057);
DISPLAY INVISIBLE (605 3057);
FORCEPROP 2 LAST CDS_LIB mstr_symbols
J 0
(650 3100);
PAINT ORANGE (650 3100);
DISPLAY INVISIBLE (650 3100);
FORCEPROP 1 LAST PATH I252
J 0
(700 3125);
DISPLAY 0.872340 (700 3125);
PAINT AQUA (700 3125);
DISPLAY INVISIBLE (700 3125);
FORCEPROP 2 LAST ROOM VDDQ_KLM_PWR_VR
J 0
(875 3200);
PAINT ORANGE (875 3200);
DISPLAY INVISIBLE (875 3200);
FORCEPROP 2 LAST BOM_COST MEM_VRD_PVPP_AB
J 0
(700 3200);
PAINT MONO (700 3200);
DISPLAY INVISIBLE (700 3200);
FORCEPROP 1 LAST VOLTAGE 1.2V
J 0
(605 3057);
DISPLAY 0.340426 (605 3057);
PAINT SKYBLUE (605 3057);
DISPLAY INVISIBLE (605 3057);
FORCEADD GND..1
(650 2325);
FORCEPROP 3 LASTPIN (650 2375) SIG_NAME GND\g
J 0
(660 2385);
DISPLAY 0.659574 (660 2385);
PAINT MONO (660 2385);
DISPLAY INVISIBLE (660 2385);
FORCEPROP 1 LAST HDL_POWER GND
J 0
(650 2475);
DISPLAY 0.893617 (650 2475);
PAINT GREEN (650 2475);
DISPLAY INVISIBLE (650 2475);
FORCEPROP 1 LAST BODY_TYPE PLUMBING
J 0
(605 2282);
DISPLAY 0.340426 (605 2282);
PAINT GREEN (605 2282);
DISPLAY INVISIBLE (605 2282);
FORCEPROP 1 LAST PATH I253
J 0
(725 2325);
DISPLAY 0.872340 (725 2325);
PAINT AQUA (725 2325);
DISPLAY INVISIBLE (725 2325);
FORCEPROP 2 LAST ROOM PVCCIN_CPU1_DECAP_VR
J 0
(100 2400);
PAINT ORANGE (100 2400);
DISPLAY INVISIBLE (100 2400);
FORCEPROP 1 LAST SIZE 1B
J 0
(725 2275);
DISPLAY 0.893617 (725 2275);
PAINT GREEN (725 2275);
DISPLAY INVISIBLE (725 2275);
FORCEPROP 2 LAST CDS_LIB mstr_symbols
J 0
(650 2325);
PAINT ORANGE (650 2325);
DISPLAY INVISIBLE (650 2325);
FORCEPROP 1 LAST VOLTAGE 0
J 0
(650 2325);
PAINT SKYBLUE (650 2325);
DISPLAY INVISIBLE (650 2325);
FORCEADD CAP_A..1
(1650 1800);
FORCEPROP 1 LASTPIN (1650 1700) $PN 2
J 0
(1660 1680);
DISPLAY 0.617021 (1660 1680);
PAINT GREEN (1660 1680);
FORCEPROP 1 LAST TOLERANCE 20%
J 0
(1700 1750);
DISPLAY 0.617021 (1700 1750);
PAINT SKYBLUE (1700 1750);
FORCEPROP 1 LAST MATERIAL X6S
J 0
(1700 1700);
DISPLAY 0.617021 (1700 1700);
PAINT SKYBLUE (1700 1700);
FORCEPROP 1 LASTPIN (1650 1900) $PN 1
J 0
(1660 1880);
DISPLAY 0.617021 (1660 1880);
PAINT GREEN (1660 1880);
FORCEPROP 1 LAST LOCATION C3D1
J 0
(1700 1900);
DISPLAY 0.617021 (1700 1900);
PAINT AQUA (1700 1900);
FORCEPROP 1 LAST VALUE 22.0UF
J 0
(1700 1850);
DISPLAY 0.617021 (1700 1850);
PAINT SKYBLUE (1700 1850);
FORCEPROP 1 LAST PART_NUMBER E15431-004
J 0
(1700 1650);
DISPLAY 0.617021 (1700 1650);
PAINT BLUE (1700 1650);
FORCEPROP 1 LAST PACK_TYPE 0603V
J 0
(1700 1600);
DISPLAY 0.617021 (1700 1600);
PAINT SKYBLUE (1700 1600);
FORCEPROP 0 LAST GROUP PWR_MLCC_CAP
J 0
(1706 1512);
DISPLAY 0.638298 (1706 1512);
PAINT BROWN (1706 1512);
DISPLAY BOTH (1706 1512);
FORCEPROP 1 LAST VOLTAGE 4V
J 0
(1700 1800);
DISPLAY 0.617021 (1700 1800);
PAINT SKYBLUE (1700 1800);
FORCEPROP 2 LAST ROOM PVCCIN_CPU1_DECAP_VR
J 0
(1700 1900);
PAINT ORANGE (1700 1900);
DISPLAY INVISIBLE (1700 1900);
FORCEPROP 2 LAST $SEC 1
J 0
(1700 2000);
PAINT MONO (1700 2000);
DISPLAY INVISIBLE (1700 2000);
FORCEPROP 2 LAST CDS_SEC 1
J 0
(1700 2000);
PAINT MONO (1700 2000);
DISPLAY INVISIBLE (1700 2000);
FORCEPROP 2 LAST CDS_LIB dev_discrete
J 0
(1650 1800);
PAINT ORANGE (1650 1800);
DISPLAY INVISIBLE (1650 1800);
FORCEPROP 2 LAST BOM_COST PROC
J 0
(1650 1800);
PAINT MONO (1650 1800);
DISPLAY INVISIBLE (1650 1800);
FORCEPROP 2 LAST CDS_LOCATION C3D1
J 0
(1700 1900);
DISPLAY 0.617021 (1700 1900);
PAINT AQUA (1700 1900);
DISPLAY INVISIBLE (1700 1900);
FORCEPROP 1 LAST PATH I255
J 0
(1700 1950);
DISPLAY 0.978723 (1700 1950);
PAINT WHITE (1700 1950);
DISPLAY INVISIBLE (1700 1950);
FORCEADD CAP_A..1
(1300 1800);
FORCEPROP 1 LAST TOLERANCE 20%
J 0
(1350 1750);
DISPLAY 0.617021 (1350 1750);
PAINT SKYBLUE (1350 1750);
FORCEPROP 1 LAST MATERIAL X6S
J 0
(1350 1700);
DISPLAY 0.617021 (1350 1700);
PAINT SKYBLUE (1350 1700);
FORCEPROP 1 LASTPIN (1300 1700) $PN 2
J 0
(1310 1680);
DISPLAY 0.787234 (1310 1680);
PAINT ORANGE (1310 1680);
FORCEPROP 1 LASTPIN (1300 1900) $PN 1
J 0
(1310 1880);
DISPLAY 0.787234 (1310 1880);
PAINT ORANGE (1310 1880);
FORCEPROP 1 LAST VOLTAGE 4V
J 0
(1350 1800);
DISPLAY 0.617021 (1350 1800);
PAINT SKYBLUE (1350 1800);
FORCEPROP 1 LAST LOCATION C2D3
J 0
(1350 1900);
DISPLAY 0.617021 (1350 1900);
PAINT AQUA (1350 1900);
FORCEPROP 1 LAST VALUE 22.0UF
J 0
(1350 1850);
DISPLAY 0.617021 (1350 1850);
PAINT SKYBLUE (1350 1850);
FORCEPROP 1 LAST PART_NUMBER E15431-004
J 0
(1350 1650);
DISPLAY 0.617021 (1350 1650);
PAINT BLUE (1350 1650);
FORCEPROP 1 LAST PACK_TYPE 0603V
J 0
(1350 1600);
DISPLAY 0.617021 (1350 1600);
PAINT SKYBLUE (1350 1600);
FORCEPROP 0 LAST GROUP PWR_MLCC_CAP
J 0
(1356 1562);
DISPLAY 0.638298 (1356 1562);
PAINT BROWN (1356 1562);
DISPLAY BOTH (1356 1562);
FORCEPROP 1 LAST PATH I256
J 0
(1350 1950);
DISPLAY 0.978723 (1350 1950);
PAINT WHITE (1350 1950);
DISPLAY INVISIBLE (1350 1950);
FORCEPROP 2 LAST ROOM PVCCIN_CPU1_DECAP_VR
J 0
(1350 1900);
PAINT ORANGE (1350 1900);
DISPLAY INVISIBLE (1350 1900);
FORCEPROP 2 LAST CDS_LIB dev_discrete
J 0
(1300 1800);
PAINT ORANGE (1300 1800);
DISPLAY INVISIBLE (1300 1800);
FORCEPROP 2 LAST BOM_COST PROC
J 0
(1300 1800);
PAINT MONO (1300 1800);
DISPLAY INVISIBLE (1300 1800);
FORCEPROP 2 LAST CDS_LOCATION C2D3
J 0
(1350 1900);
DISPLAY 0.617021 (1350 1900);
PAINT AQUA (1350 1900);
DISPLAY INVISIBLE (1350 1900);
FORCEPROP 2 LAST SEC_TYPE 0603V
J 0
(1350 2000);
DISPLAY 1.021277 (1350 2000);
PAINT ORANGE (1350 2000);
DISPLAY INVISIBLE (1350 2000);
FORCEPROP 2 LAST SEC 1
J 0
(1350 2000);
PAINT MONO (1350 2000);
DISPLAY INVISIBLE (1350 2000);
FORCEADD CAP_A..1
(950 1800);
FORCEPROP 1 LASTPIN (950 1700) $PN 2
J 0
(960 1680);
DISPLAY 0.787234 (960 1680);
PAINT ORANGE (960 1680);
FORCEPROP 1 LAST MATERIAL X6S
J 0
(1000 1700);
DISPLAY 0.617021 (1000 1700);
PAINT SKYBLUE (1000 1700);
FORCEPROP 1 LAST VOLTAGE 4V
J 0
(1000 1800);
DISPLAY 0.617021 (1000 1800);
PAINT SKYBLUE (1000 1800);
FORCEPROP 1 LAST TOLERANCE 20%
J 0
(1000 1750);
DISPLAY 0.617021 (1000 1750);
PAINT SKYBLUE (1000 1750);
FORCEPROP 1 LAST LOCATION C2D2
J 0
(1000 1900);
DISPLAY 0.617021 (1000 1900);
PAINT AQUA (1000 1900);
FORCEPROP 1 LASTPIN (950 1900) $PN 1
J 0
(960 1880);
DISPLAY 0.787234 (960 1880);
PAINT ORANGE (960 1880);
FORCEPROP 1 LAST VALUE 22.0UF
J 0
(1000 1850);
DISPLAY 0.617021 (1000 1850);
PAINT SKYBLUE (1000 1850);
FORCEPROP 1 LAST PART_NUMBER E15431-004
J 0
(1000 1650);
DISPLAY 0.617021 (1000 1650);
PAINT BLUE (1000 1650);
FORCEPROP 1 LAST PACK_TYPE 0603V
J 0
(1000 1600);
DISPLAY 0.617021 (1000 1600);
PAINT SKYBLUE (1000 1600);
FORCEPROP 0 LAST GROUP PWR_MLCC_CAP
J 0
(1006 1512);
DISPLAY 0.638298 (1006 1512);
PAINT BROWN (1006 1512);
DISPLAY BOTH (1006 1512);
FORCEPROP 1 LAST PATH I257
J 0
(1000 1950);
DISPLAY 0.978723 (1000 1950);
PAINT WHITE (1000 1950);
DISPLAY INVISIBLE (1000 1950);
FORCEPROP 2 LAST ROOM PVCCIN_CPU1_DECAP_VR
J 0
(1000 1900);
PAINT ORANGE (1000 1900);
DISPLAY INVISIBLE (1000 1900);
FORCEPROP 2 LAST CDS_LIB dev_discrete
J 0
(950 1800);
PAINT ORANGE (950 1800);
DISPLAY INVISIBLE (950 1800);
FORCEPROP 2 LAST BOM_COST PROC
J 0
(950 1800);
PAINT MONO (950 1800);
DISPLAY INVISIBLE (950 1800);
FORCEPROP 2 LAST CDS_LOCATION C2D2
J 0
(1000 1900);
DISPLAY 0.617021 (1000 1900);
PAINT AQUA (1000 1900);
DISPLAY INVISIBLE (1000 1900);
FORCEPROP 2 LAST SEC_TYPE 0603V
J 0
(1000 2000);
DISPLAY 1.021277 (1000 2000);
PAINT ORANGE (1000 2000);
DISPLAY INVISIBLE (1000 2000);
FORCEPROP 2 LAST SEC 1
J 0
(1000 2000);
PAINT MONO (1000 2000);
DISPLAY INVISIBLE (1000 2000);
FORCEADD CAP_A..1
(600 1800);
FORCEPROP 1 LASTPIN (600 1700) $PN 2
J 0
(610 1680);
DISPLAY 0.617021 (610 1680);
PAINT GREEN (610 1680);
FORCEPROP 1 LASTPIN (600 1900) $PN 1
J 0
(610 1880);
DISPLAY 0.617021 (610 1880);
PAINT GREEN (610 1880);
FORCEPROP 1 LAST LOCATION C2D1
J 0
(650 1900);
DISPLAY 0.617021 (650 1900);
PAINT AQUA (650 1900);
FORCEPROP 1 LAST VOLTAGE 4V
J 0
(650 1800);
DISPLAY 0.617021 (650 1800);
PAINT SKYBLUE (650 1800);
FORCEPROP 1 LAST PACK_TYPE 0603V
J 0
(650 1600);
DISPLAY 0.617021 (650 1600);
PAINT SKYBLUE (650 1600);
FORCEPROP 1 LAST PART_NUMBER E15431-004
J 0
(650 1650);
DISPLAY 0.617021 (650 1650);
PAINT BLUE (650 1650);
FORCEPROP 1 LAST VALUE 22.0UF
J 0
(650 1850);
DISPLAY 0.617021 (650 1850);
PAINT SKYBLUE (650 1850);
FORCEPROP 1 LAST TOLERANCE 20%
J 0
(650 1750);
DISPLAY 0.617021 (650 1750);
PAINT SKYBLUE (650 1750);
FORCEPROP 1 LAST MATERIAL X6S
J 0
(650 1700);
DISPLAY 0.617021 (650 1700);
PAINT SKYBLUE (650 1700);
FORCEPROP 0 LAST GROUP PWR_MLCC_CAP
J 0
(656 1562);
DISPLAY 0.638298 (656 1562);
PAINT BROWN (656 1562);
DISPLAY BOTH (656 1562);
FORCEPROP 1 LAST PATH I258
J 0
(650 1950);
DISPLAY 0.978723 (650 1950);
PAINT WHITE (650 1950);
DISPLAY INVISIBLE (650 1950);
FORCEPROP 2 LAST CDS_LOCATION C2D1
J 0
(650 1900);
DISPLAY 0.617021 (650 1900);
PAINT AQUA (650 1900);
DISPLAY INVISIBLE (650 1900);
FORCEPROP 2 LAST BOM_COST PROC
J 0
(600 1800);
PAINT MONO (600 1800);
DISPLAY INVISIBLE (600 1800);
FORCEPROP 2 LAST CDS_LIB dev_discrete
J 0
(600 1800);
PAINT ORANGE (600 1800);
DISPLAY INVISIBLE (600 1800);
FORCEPROP 2 LAST CDS_SEC 1
J 0
(650 2000);
PAINT MONO (650 2000);
DISPLAY INVISIBLE (650 2000);
FORCEPROP 2 LAST $SEC 1
J 0
(650 2000);
PAINT MONO (650 2000);
DISPLAY INVISIBLE (650 2000);
FORCEPROP 2 LAST ROOM PVCCIN_CPU1_DECAP_VR
J 0
(650 1900);
PAINT ORANGE (650 1900);
DISPLAY INVISIBLE (650 1900);
FORCEADD GND..1
(1650 1450);
FORCEPROP 3 LASTPIN (1650 1500) SIG_NAME GND\g
J 0
(1660 1510);
DISPLAY 0.659574 (1660 1510);
PAINT MONO (1660 1510);
DISPLAY INVISIBLE (1660 1510);
FORCEPROP 1 LAST PATH I259
J 0
(1725 1450);
DISPLAY 0.872340 (1725 1450);
PAINT AQUA (1725 1450);
DISPLAY INVISIBLE (1725 1450);
FORCEPROP 2 LAST ROOM PVCCIN_CPU1_DECAP_VR
J 0
(1100 1525);
PAINT ORANGE (1100 1525);
DISPLAY INVISIBLE (1100 1525);
FORCEPROP 1 LAST SIZE 1B
J 0
(1725 1400);
DISPLAY 0.893617 (1725 1400);
PAINT GREEN (1725 1400);
DISPLAY INVISIBLE (1725 1400);
FORCEPROP 2 LAST CDS_LIB mstr_symbols
J 0
(1650 1450);
PAINT ORANGE (1650 1450);
DISPLAY INVISIBLE (1650 1450);
FORCEPROP 1 LAST VOLTAGE 0
J 0
(1650 1450);
PAINT SKYBLUE (1650 1450);
DISPLAY INVISIBLE (1650 1450);
FORCEPROP 1 LAST BODY_TYPE PLUMBING
J 0
(1605 1407);
DISPLAY 0.340426 (1605 1407);
PAINT GREEN (1605 1407);
DISPLAY INVISIBLE (1605 1407);
FORCEPROP 1 LAST HDL_POWER GND
J 0
(1650 1600);
DISPLAY 0.893617 (1650 1600);
PAINT GREEN (1650 1600);
DISPLAY INVISIBLE (1650 1600);
FORCEADD PVDDQ_KLM..1
(600 2050);
FORCEPROP 3 LASTPIN (600 2000) SIG_NAME PVDDQ_KLM\g
J 0
(610 2010);
DISPLAY 0.659574 (610 2010);
PAINT MONO (610 2010);
DISPLAY INVISIBLE (610 2010);
FORCEPROP 1 LAST VOLTAGE 1.2V
J 0
(555 2007);
DISPLAY 0.340426 (555 2007);
PAINT SKYBLUE (555 2007);
DISPLAY INVISIBLE (555 2007);
FORCEPROP 2 LAST BOM_COST MEM_VRD_PVPP_AB
J 0
(650 2150);
PAINT MONO (650 2150);
DISPLAY INVISIBLE (650 2150);
FORCEPROP 2 LAST ROOM VDDQ_KLM_PWR_VR
J 0
(825 2150);
PAINT ORANGE (825 2150);
DISPLAY INVISIBLE (825 2150);
FORCEPROP 2 LAST CDS_LIB mstr_symbols
J 0
(600 2050);
PAINT MONO (600 2050);
DISPLAY INVISIBLE (600 2050);
FORCEPROP 1 LAST PATH I260
J 0
(650 2075);
DISPLAY 0.872340 (650 2075);
PAINT AQUA (650 2075);
DISPLAY INVISIBLE (650 2075);
FORCEPROP 1 LAST BODY_TYPE PLUMBING
J 0
(555 2007);
DISPLAY 0.340426 (555 2007);
PAINT GREEN (555 2007);
DISPLAY INVISIBLE (555 2007);
FORCEPROP 1 LAST HDL_POWER PVDDQ_KLM
J 1
(600 2100);
DISPLAY 0.872340 (600 2100);
PAINT GREEN (600 2100);
DISPLAY INVISIBLE (600 2100);
FORCEADD GND..1
(525 500);
FORCEPROP 3 LASTPIN (525 550) SIG_NAME GND\g
J 0
(535 560);
DISPLAY 0.659574 (535 560);
PAINT MONO (535 560);
DISPLAY INVISIBLE (535 560);
FORCEPROP 1 LAST VOLTAGE 0
J 0
(525 500);
PAINT SKYBLUE (525 500);
DISPLAY INVISIBLE (525 500);
FORCEPROP 1 LAST SIZE 1B
J 0
(600 450);
DISPLAY 0.893617 (600 450);
PAINT GREEN (600 450);
DISPLAY INVISIBLE (600 450);
FORCEPROP 2 LAST CDS_LIB mstr_symbols
J 0
(525 500);
PAINT ORANGE (525 500);
DISPLAY INVISIBLE (525 500);
FORCEPROP 2 LAST ROOM PVCCIN_CPU1_DECAP_VR
J 0
(-25 575);
PAINT ORANGE (-25 575);
DISPLAY INVISIBLE (-25 575);
FORCEPROP 1 LAST PATH I262
J 0
(600 500);
DISPLAY 0.872340 (600 500);
PAINT AQUA (600 500);
DISPLAY INVISIBLE (600 500);
FORCEPROP 1 LAST BODY_TYPE PLUMBING
J 0
(480 457);
DISPLAY 0.340426 (480 457);
PAINT GREEN (480 457);
DISPLAY INVISIBLE (480 457);
FORCEPROP 1 LAST HDL_POWER GND
J 0
(525 650);
DISPLAY 0.893617 (525 650);
PAINT GREEN (525 650);
DISPLAY INVISIBLE (525 650);
FORCEADD PVDDQ_KLM..1
(525 950);
FORCEPROP 3 LASTPIN (525 900) SIG_NAME PVDDQ_KLM\g
J 0
(535 910);
DISPLAY 0.659574 (535 910);
PAINT MONO (535 910);
DISPLAY INVISIBLE (535 910);
FORCEPROP 1 LAST PATH I263
J 0
(575 975);
DISPLAY 0.872340 (575 975);
PAINT AQUA (575 975);
DISPLAY INVISIBLE (575 975);
FORCEPROP 1 LAST VOLTAGE 1.2V
J 0
(480 907);
DISPLAY 0.340426 (480 907);
PAINT SKYBLUE (480 907);
DISPLAY INVISIBLE (480 907);
FORCEPROP 2 LAST BOM_COST MEM_VRD_PVPP_AB
J 0
(575 1050);
PAINT MONO (575 1050);
DISPLAY INVISIBLE (575 1050);
FORCEPROP 2 LAST ROOM VDDQ_KLM_PWR_VR
J 0
(750 1050);
PAINT ORANGE (750 1050);
DISPLAY INVISIBLE (750 1050);
FORCEPROP 2 LAST CDS_LIB mstr_symbols
J 0
(525 950);
PAINT MONO (525 950);
DISPLAY INVISIBLE (525 950);
FORCEPROP 1 LAST BODY_TYPE PLUMBING
J 0
(480 907);
DISPLAY 0.340426 (480 907);
PAINT GREEN (480 907);
DISPLAY INVISIBLE (480 907);
FORCEPROP 1 LAST HDL_POWER PVDDQ_KLM
J 1
(525 1000);
DISPLAY 0.872340 (525 1000);
PAINT GREEN (525 1000);
DISPLAY INVISIBLE (525 1000);
FORCEADD CAP_A..1
(-1300 2975);
FORCEPROP 0 LAST GROUP PWR_MLCC_CAP
J 0
(-1244 2737);
DISPLAY 0.638298 (-1244 2737);
PAINT BROWN (-1244 2737);
DISPLAY BOTH (-1244 2737);
FORCEPROP 1 LAST VOLTAGE 4V
J 0
(-1250 2975);
DISPLAY 0.617021 (-1250 2975);
PAINT SKYBLUE (-1250 2975);
FORCEPROP 1 LASTPIN (-1300 2875) $PN 2
J 0
(-1290 2855);
DISPLAY 0.617021 (-1290 2855);
PAINT GREEN (-1290 2855);
FORCEPROP 1 LASTPIN (-1300 3075) $PN 1
J 0
(-1290 3055);
DISPLAY 0.617021 (-1290 3055);
PAINT GREEN (-1290 3055);
FORCEPROP 1 LAST LOCATION C2D7
J 0
(-1250 3075);
DISPLAY 0.617021 (-1250 3075);
PAINT AQUA (-1250 3075);
FORCEPROP 1 LAST TOLERANCE 20%
J 0
(-1250 2925);
DISPLAY 0.617021 (-1250 2925);
PAINT SKYBLUE (-1250 2925);
FORCEPROP 1 LAST PACK_TYPE 0603V
J 0
(-1250 2775);
DISPLAY 0.617021 (-1250 2775);
PAINT SKYBLUE (-1250 2775);
FORCEPROP 1 LAST PART_NUMBER E15431-004
J 0
(-1250 2825);
DISPLAY 0.617021 (-1250 2825);
PAINT BLUE (-1250 2825);
FORCEPROP 1 LAST MATERIAL X6S
J 0
(-1250 2875);
DISPLAY 0.617021 (-1250 2875);
PAINT SKYBLUE (-1250 2875);
FORCEPROP 1 LAST VALUE 22.0UF
J 0
(-1250 3025);
DISPLAY 0.617021 (-1250 3025);
PAINT SKYBLUE (-1250 3025);
FORCEPROP 1 LAST PATH I264
J 0
(-1250 3125);
DISPLAY 0.978723 (-1250 3125);
PAINT WHITE (-1250 3125);
DISPLAY INVISIBLE (-1250 3125);
FORCEPROP 2 LAST ROOM PVCCIN_CPU0_DECAP_VR
J 0
(-1250 3125);
DISPLAY 1.021277 (-1250 3125);
PAINT ORANGE (-1250 3125);
DISPLAY INVISIBLE (-1250 3125);
FORCEPROP 2 LAST $SEC 1
J 0
(-1250 3175);
PAINT MONO (-1250 3175);
DISPLAY INVISIBLE (-1250 3175);
FORCEPROP 2 LAST CDS_SEC 1
J 0
(-1250 3175);
PAINT MONO (-1250 3175);
DISPLAY INVISIBLE (-1250 3175);
FORCEPROP 2 LAST CDS_LIB dev_discrete
J 0
(-1300 2975);
PAINT ORANGE (-1300 2975);
DISPLAY INVISIBLE (-1300 2975);
FORCEPROP 2 LAST BOM_COST PROC_SOCKET
J 0
(-1250 3175);
DISPLAY 1.021277 (-1250 3175);
PAINT ORANGE (-1250 3175);
DISPLAY INVISIBLE (-1250 3175);
FORCEPROP 2 LAST CDS_LOCATION C2D7
J 0
(-1250 3075);
DISPLAY 0.617021 (-1250 3075);
PAINT AQUA (-1250 3075);
DISPLAY INVISIBLE (-1250 3075);
FORCEADD CAP_A..1
(-950 2975);
FORCEPROP 1 LAST LOCATION C2D4
J 0
(-900 3075);
DISPLAY 0.617021 (-900 3075);
PAINT AQUA (-900 3075);
FORCEPROP 1 LAST PACK_TYPE 0603V
J 0
(-900 2775);
DISPLAY 0.617021 (-900 2775);
PAINT SKYBLUE (-900 2775);
FORCEPROP 1 LAST MATERIAL X6S
J 0
(-900 2875);
DISPLAY 0.617021 (-900 2875);
PAINT SKYBLUE (-900 2875);
FORCEPROP 1 LAST VOLTAGE 4V
J 0
(-900 2975);
DISPLAY 0.617021 (-900 2975);
PAINT SKYBLUE (-900 2975);
FORCEPROP 1 LAST VALUE 22.0UF
J 0
(-900 3025);
DISPLAY 0.617021 (-900 3025);
PAINT SKYBLUE (-900 3025);
FORCEPROP 1 LAST PART_NUMBER E15431-004
J 0
(-900 2825);
DISPLAY 0.617021 (-900 2825);
PAINT BLUE (-900 2825);
FORCEPROP 1 LASTPIN (-950 2875) $PN 2
J 0
(-940 2855);
DISPLAY 0.617021 (-940 2855);
PAINT GREEN (-940 2855);
FORCEPROP 1 LASTPIN (-950 3075) $PN 1
J 0
(-940 3055);
DISPLAY 0.617021 (-940 3055);
PAINT GREEN (-940 3055);
FORCEPROP 0 LAST GROUP PWR_MLCC_CAP
J 0
(-894 2687);
DISPLAY 0.638298 (-894 2687);
PAINT BROWN (-894 2687);
DISPLAY BOTH (-894 2687);
FORCEPROP 1 LAST TOLERANCE 20%
J 0
(-900 2925);
DISPLAY 0.617021 (-900 2925);
PAINT SKYBLUE (-900 2925);
FORCEPROP 1 LAST PATH I265
J 0
(-900 3125);
DISPLAY 0.978723 (-900 3125);
PAINT WHITE (-900 3125);
DISPLAY INVISIBLE (-900 3125);
FORCEPROP 2 LAST ROOM PVCCIN_CPU0_DECAP_VR
J 0
(-900 3125);
DISPLAY 1.021277 (-900 3125);
PAINT ORANGE (-900 3125);
DISPLAY INVISIBLE (-900 3125);
FORCEPROP 2 LAST $SEC 1
J 0
(-900 3175);
PAINT MONO (-900 3175);
DISPLAY INVISIBLE (-900 3175);
FORCEPROP 2 LAST CDS_SEC 1
J 0
(-900 3175);
PAINT MONO (-900 3175);
DISPLAY INVISIBLE (-900 3175);
FORCEPROP 2 LAST CDS_LIB dev_discrete
J 0
(-950 2975);
PAINT ORANGE (-950 2975);
DISPLAY INVISIBLE (-950 2975);
FORCEPROP 2 LAST BOM_COST PROC_SOCKET
J 0
(-900 3175);
DISPLAY 1.021277 (-900 3175);
PAINT ORANGE (-900 3175);
DISPLAY INVISIBLE (-900 3175);
FORCEPROP 2 LAST CDS_LOCATION C2D4
J 0
(-900 3075);
DISPLAY 0.617021 (-900 3075);
PAINT AQUA (-900 3075);
DISPLAY INVISIBLE (-900 3075);
FORCEADD CAP_A..1
(-600 2975);
FORCEPROP 1 LASTPIN (-600 2875) $PN 2
J 0
(-590 2855);
DISPLAY 0.617021 (-590 2855);
PAINT GREEN (-590 2855);
FORCEPROP 1 LAST VOLTAGE 4V
J 0
(-550 2975);
DISPLAY 0.617021 (-550 2975);
PAINT SKYBLUE (-550 2975);
FORCEPROP 1 LAST TOLERANCE 20%
J 0
(-550 2925);
DISPLAY 0.617021 (-550 2925);
PAINT SKYBLUE (-550 2925);
FORCEPROP 1 LAST PACK_TYPE 0603V
J 0
(-550 2775);
DISPLAY 0.617021 (-550 2775);
PAINT SKYBLUE (-550 2775);
FORCEPROP 1 LAST MATERIAL X6S
J 0
(-550 2875);
DISPLAY 0.617021 (-550 2875);
PAINT SKYBLUE (-550 2875);
FORCEPROP 1 LAST PART_NUMBER E15431-004
J 0
(-550 2825);
DISPLAY 0.617021 (-550 2825);
PAINT BLUE (-550 2825);
FORCEPROP 1 LASTPIN (-600 3075) $PN 1
J 0
(-590 3055);
DISPLAY 0.617021 (-590 3055);
PAINT GREEN (-590 3055);
FORCEPROP 1 LAST LOCATION C2D5
J 0
(-550 3075);
DISPLAY 0.617021 (-550 3075);
PAINT AQUA (-550 3075);
FORCEPROP 1 LAST VALUE 22.0UF
J 0
(-550 3025);
DISPLAY 0.617021 (-550 3025);
PAINT SKYBLUE (-550 3025);
FORCEPROP 0 LAST GROUP PWR_MLCC_CAP
J 0
(-544 2737);
DISPLAY 0.638298 (-544 2737);
PAINT BROWN (-544 2737);
DISPLAY BOTH (-544 2737);
FORCEPROP 1 LAST PATH I266
J 0
(-550 3125);
DISPLAY 0.978723 (-550 3125);
PAINT WHITE (-550 3125);
DISPLAY INVISIBLE (-550 3125);
FORCEPROP 2 LAST ROOM PVCCIN_CPU0_DECAP_VR
J 0
(-550 3125);
DISPLAY 1.021277 (-550 3125);
PAINT ORANGE (-550 3125);
DISPLAY INVISIBLE (-550 3125);
FORCEPROP 2 LAST $SEC 1
J 0
(-550 3175);
PAINT MONO (-550 3175);
DISPLAY INVISIBLE (-550 3175);
FORCEPROP 2 LAST CDS_SEC 1
J 0
(-550 3175);
PAINT MONO (-550 3175);
DISPLAY INVISIBLE (-550 3175);
FORCEPROP 2 LAST CDS_LIB dev_discrete
J 0
(-600 2975);
PAINT ORANGE (-600 2975);
DISPLAY INVISIBLE (-600 2975);
FORCEPROP 2 LAST BOM_COST PROC_SOCKET
J 0
(-550 3175);
DISPLAY 1.021277 (-550 3175);
PAINT ORANGE (-550 3175);
DISPLAY INVISIBLE (-550 3175);
FORCEPROP 2 LAST CDS_LOCATION C2D5
J 0
(-550 3075);
DISPLAY 0.617021 (-550 3075);
PAINT AQUA (-550 3075);
DISPLAY INVISIBLE (-550 3075);
FORCEADD CAP_A..1
(-250 2975);
FORCEPROP 1 LAST TOLERANCE 20%
J 0
(-200 2925);
DISPLAY 0.617021 (-200 2925);
PAINT SKYBLUE (-200 2925);
FORCEPROP 1 LASTPIN (-250 2875) $PN 2
J 0
(-240 2855);
DISPLAY 0.617021 (-240 2855);
PAINT GREEN (-240 2855);
FORCEPROP 1 LAST MATERIAL X6S
J 0
(-200 2875);
DISPLAY 0.617021 (-200 2875);
PAINT SKYBLUE (-200 2875);
FORCEPROP 1 LASTPIN (-250 3075) $PN 1
J 0
(-240 3055);
DISPLAY 0.617021 (-240 3055);
PAINT GREEN (-240 3055);
FORCEPROP 1 LAST PART_NUMBER E15431-004
J 0
(-200 2825);
DISPLAY 0.617021 (-200 2825);
PAINT BLUE (-200 2825);
FORCEPROP 1 LAST LOCATION C2D6
J 0
(-200 3075);
DISPLAY 0.617021 (-200 3075);
PAINT AQUA (-200 3075);
FORCEPROP 1 LAST VOLTAGE 4V
J 0
(-200 2975);
DISPLAY 0.617021 (-200 2975);
PAINT SKYBLUE (-200 2975);
FORCEPROP 0 LAST GROUP PWR_MLCC_CAP
J 0
(-194 2687);
DISPLAY 0.638298 (-194 2687);
PAINT BROWN (-194 2687);
DISPLAY BOTH (-194 2687);
FORCEPROP 1 LAST VALUE 22.0UF
J 0
(-200 3025);
DISPLAY 0.617021 (-200 3025);
PAINT SKYBLUE (-200 3025);
FORCEPROP 1 LAST PACK_TYPE 0603V
J 0
(-200 2775);
DISPLAY 0.617021 (-200 2775);
PAINT SKYBLUE (-200 2775);
FORCEPROP 1 LAST PATH I267
J 0
(-200 3125);
DISPLAY 0.978723 (-200 3125);
PAINT WHITE (-200 3125);
DISPLAY INVISIBLE (-200 3125);
FORCEPROP 2 LAST ROOM PVCCIN_CPU0_DECAP_VR
J 0
(-200 3125);
DISPLAY 1.021277 (-200 3125);
PAINT ORANGE (-200 3125);
DISPLAY INVISIBLE (-200 3125);
FORCEPROP 2 LAST $SEC 1
J 0
(-200 3175);
PAINT MONO (-200 3175);
DISPLAY INVISIBLE (-200 3175);
FORCEPROP 2 LAST CDS_SEC 1
J 0
(-200 3175);
PAINT MONO (-200 3175);
DISPLAY INVISIBLE (-200 3175);
FORCEPROP 2 LAST CDS_LIB dev_discrete
J 0
(-250 2975);
PAINT ORANGE (-250 2975);
DISPLAY INVISIBLE (-250 2975);
FORCEPROP 2 LAST BOM_COST PROC_SOCKET
J 0
(-200 3175);
DISPLAY 1.021277 (-200 3175);
PAINT ORANGE (-200 3175);
DISPLAY INVISIBLE (-200 3175);
FORCEPROP 2 LAST CDS_LOCATION C2D6
J 0
(-200 3075);
DISPLAY 0.617021 (-200 3075);
PAINT AQUA (-200 3075);
DISPLAY INVISIBLE (-200 3075);
FORCEADD CAP_A..1
(-2250 -75);
FORCEPROP 0 LAST BOM_SS E15431-004
J 0
(-2220 -354);
DISPLAY 0.510638 (-2220 -354);
PAINT BROWN (-2220 -354);
DISPLAY BOTH (-2220 -354);
FORCEPROP 1 LAST PACK_TYPE 0603V
J 0
(-2200 -275);
DISPLAY 0.617021 (-2200 -275);
PAINT SKYBLUE (-2200 -275);
FORCEPROP 1 LAST PART_NUMBER 602433-106
J 0
(-2200 -225);
DISPLAY 0.617021 (-2200 -225);
PAINT BLUE (-2200 -225);
FORCEPROP 0 LAST GROUP PWR_MLCC_CAP
J 0
(-2219 -438);
DISPLAY 0.638298 (-2219 -438);
PAINT BROWN (-2219 -438);
DISPLAY BOTH (-2219 -438);
FORCEPROP 1 LAST TOLERANCE 20%
J 0
(-2200 -125);
DISPLAY 0.617021 (-2200 -125);
PAINT SKYBLUE (-2200 -125);
FORCEPROP 1 LAST MATERIAL X5R
J 0
(-2200 -175);
DISPLAY 0.617021 (-2200 -175);
PAINT SKYBLUE (-2200 -175);
FORCEPROP 1 LAST LOCATION C7L5
J 0
(-2200 25);
DISPLAY 0.617021 (-2200 25);
PAINT AQUA (-2200 25);
FORCEPROP 1 LAST VOLTAGE 4V
J 0
(-2200 -75);
DISPLAY 0.617021 (-2200 -75);
PAINT SKYBLUE (-2200 -75);
FORCEPROP 1 LAST VALUE 47UF
J 0
(-2200 -25);
DISPLAY 0.617021 (-2200 -25);
PAINT SKYBLUE (-2200 -25);
FORCEPROP 1 LASTPIN (-2250 -175) $PN 2
J 0
(-2240 -195);
DISPLAY 0.617021 (-2240 -195);
PAINT ORANGE (-2240 -195);
FORCEPROP 1 LASTPIN (-2250 25) $PN 1
J 0
(-2240 5);
DISPLAY 0.617021 (-2240 5);
PAINT ORANGE (-2240 5);
FORCEPROP 1 LAST PATH I268
J 0
(-2200 75);
DISPLAY 0.978723 (-2200 75);
PAINT WHITE (-2200 75);
DISPLAY INVISIBLE (-2200 75);
FORCEPROP 2 LAST SEC_TYPE 0603V
J 0
(-2200 125);
DISPLAY 1.021277 (-2200 125);
PAINT ORANGE (-2200 125);
DISPLAY INVISIBLE (-2200 125);
FORCEPROP 2 LAST SEC 1
J 0
(-2200 125);
DISPLAY 0.680851 (-2200 125);
PAINT MONO (-2200 125);
DISPLAY INVISIBLE (-2200 125);
FORCEPROP 2 LAST CDS_LOCATION C7L5
J 0
(-2200 25);
DISPLAY 0.617021 (-2200 25);
PAINT AQUA (-2200 25);
DISPLAY INVISIBLE (-2200 25);
FORCEPROP 2 LAST CDS_SEC 1
J 0
(-2200 75);
PAINT ORANGE (-2200 75);
DISPLAY INVISIBLE (-2200 75);
FORCEPROP 2 LAST CDS_LIB dev_discrete
J 0
(-2250 -75);
PAINT ORANGE (-2250 -75);
DISPLAY INVISIBLE (-2250 -75);
FORCEADD CAP_A..1
(-1950 -75);
FORCEPROP 0 LAST BOM_SS E15431-004
J 0
(-1942 -402);
DISPLAY 0.510638 (-1942 -402);
PAINT BROWN (-1942 -402);
DISPLAY BOTH (-1942 -402);
FORCEPROP 1 LAST PACK_TYPE 0603V
J 0
(-1900 -275);
DISPLAY 0.617021 (-1900 -275);
PAINT SKYBLUE (-1900 -275);
FORCEPROP 1 LAST PART_NUMBER 602433-106
J 0
(-1900 -225);
DISPLAY 0.617021 (-1900 -225);
PAINT BLUE (-1900 -225);
FORCEPROP 0 LAST GROUP PWR_MLCC_CAP
J 0
(-1894 -488);
DISPLAY 0.638298 (-1894 -488);
PAINT BROWN (-1894 -488);
DISPLAY BOTH (-1894 -488);
FORCEPROP 1 LAST VALUE 47UF
J 0
(-1900 -25);
DISPLAY 0.617021 (-1900 -25);
PAINT SKYBLUE (-1900 -25);
FORCEPROP 1 LAST MATERIAL X5R
J 0
(-1900 -175);
DISPLAY 0.617021 (-1900 -175);
PAINT SKYBLUE (-1900 -175);
FORCEPROP 1 LASTPIN (-1950 25) $PN 1
J 0
(-1940 5);
DISPLAY 0.617021 (-1940 5);
PAINT ORANGE (-1940 5);
FORCEPROP 1 LAST TOLERANCE 20%
J 0
(-1900 -125);
DISPLAY 0.617021 (-1900 -125);
PAINT SKYBLUE (-1900 -125);
FORCEPROP 1 LAST VOLTAGE 4V
J 0
(-1900 -75);
DISPLAY 0.617021 (-1900 -75);
PAINT SKYBLUE (-1900 -75);
FORCEPROP 1 LAST LOCATION C3A6
J 0
(-1900 25);
DISPLAY 0.617021 (-1900 25);
PAINT AQUA (-1900 25);
FORCEPROP 1 LASTPIN (-1950 -175) $PN 2
J 0
(-1940 -195);
DISPLAY 0.617021 (-1940 -195);
PAINT ORANGE (-1940 -195);
FORCEPROP 1 LAST PATH I269
J 0
(-1900 75);
DISPLAY 0.978723 (-1900 75);
PAINT WHITE (-1900 75);
DISPLAY INVISIBLE (-1900 75);
FORCEPROP 2 LAST CDS_LIB dev_discrete
J 0
(-1950 -75);
PAINT ORANGE (-1950 -75);
DISPLAY INVISIBLE (-1950 -75);
FORCEPROP 2 LAST SEC 1
J 0
(-1900 125);
DISPLAY 0.680851 (-1900 125);
PAINT MONO (-1900 125);
DISPLAY INVISIBLE (-1900 125);
FORCEPROP 2 LAST SEC_TYPE 0603V
J 0
(-1900 125);
DISPLAY 1.021277 (-1900 125);
PAINT ORANGE (-1900 125);
DISPLAY INVISIBLE (-1900 125);
FORCEPROP 2 LAST CDS_SEC 1
J 0
(-1900 75);
PAINT ORANGE (-1900 75);
DISPLAY INVISIBLE (-1900 75);
FORCEPROP 2 LAST CDS_LOCATION C3A6
J 0
(-1900 25);
DISPLAY 0.617021 (-1900 25);
PAINT AQUA (-1900 25);
DISPLAY INVISIBLE (-1900 25);
FORCEADD CAP_A..1
(-1650 -75);
FORCEPROP 0 LAST BOM_SS E15431-004
J 0
(-1629 -339);
DISPLAY 0.510638 (-1629 -339);
PAINT BROWN (-1629 -339);
DISPLAY BOTH (-1629 -339);
FORCEPROP 1 LAST TOLERANCE 20%
J 0
(-1600 -125);
DISPLAY 0.617021 (-1600 -125);
PAINT SKYBLUE (-1600 -125);
FORCEPROP 1 LAST MATERIAL X5R
J 0
(-1600 -175);
DISPLAY 0.617021 (-1600 -175);
PAINT SKYBLUE (-1600 -175);
FORCEPROP 1 LASTPIN (-1650 -175) $PN 2
J 0
(-1640 -195);
DISPLAY 0.617021 (-1640 -195);
PAINT ORANGE (-1640 -195);
FORCEPROP 0 LAST GROUP PWR_MLCC_CAP
J 0
(-1594 -438);
DISPLAY 0.638298 (-1594 -438);
PAINT BROWN (-1594 -438);
DISPLAY BOTH (-1594 -438);
FORCEPROP 1 LASTPIN (-1650 25) $PN 1
J 0
(-1640 5);
DISPLAY 0.617021 (-1640 5);
PAINT ORANGE (-1640 5);
FORCEPROP 1 LAST VOLTAGE 4V
J 0
(-1600 -75);
DISPLAY 0.617021 (-1600 -75);
PAINT SKYBLUE (-1600 -75);
FORCEPROP 1 LAST VALUE 47UF
J 0
(-1600 -25);
DISPLAY 0.617021 (-1600 -25);
PAINT SKYBLUE (-1600 -25);
FORCEPROP 1 LAST LOCATION C3A5
J 0
(-1600 25);
DISPLAY 0.617021 (-1600 25);
PAINT AQUA (-1600 25);
FORCEPROP 1 LAST PACK_TYPE 0603V
J 0
(-1600 -275);
DISPLAY 0.617021 (-1600 -275);
PAINT SKYBLUE (-1600 -275);
FORCEPROP 1 LAST PART_NUMBER 602433-106
J 0
(-1600 -225);
DISPLAY 0.617021 (-1600 -225);
PAINT BLUE (-1600 -225);
FORCEPROP 1 LAST PATH I270
J 0
(-1600 75);
DISPLAY 0.978723 (-1600 75);
PAINT WHITE (-1600 75);
DISPLAY INVISIBLE (-1600 75);
FORCEPROP 2 LAST CDS_LIB dev_discrete
J 0
(-1650 -75);
PAINT ORANGE (-1650 -75);
DISPLAY INVISIBLE (-1650 -75);
FORCEPROP 2 LAST SEC 1
J 0
(-1600 125);
DISPLAY 0.680851 (-1600 125);
PAINT MONO (-1600 125);
DISPLAY INVISIBLE (-1600 125);
FORCEPROP 2 LAST SEC_TYPE 0603V
J 0
(-1600 125);
DISPLAY 1.021277 (-1600 125);
PAINT ORANGE (-1600 125);
DISPLAY INVISIBLE (-1600 125);
FORCEPROP 2 LAST CDS_SEC 1
J 0
(-1600 75);
PAINT ORANGE (-1600 75);
DISPLAY INVISIBLE (-1600 75);
FORCEPROP 2 LAST CDS_LOCATION C3A5
J 0
(-1600 25);
DISPLAY 0.617021 (-1600 25);
PAINT AQUA (-1600 25);
DISPLAY INVISIBLE (-1600 25);
FORCEADD CAP_A..1
(-1375 -75);
FORCEPROP 0 LAST BOM_SS E15431-004
J 0
(-1365 -409);
DISPLAY 0.510638 (-1365 -409);
PAINT BROWN (-1365 -409);
DISPLAY BOTH (-1365 -409);
FORCEPROP 1 LAST LOCATION C2A15
J 0
(-1325 25);
DISPLAY 0.617021 (-1325 25);
PAINT AQUA (-1325 25);
FORCEPROP 1 LASTPIN (-1375 25) $PN 1
J 0
(-1365 5);
DISPLAY 0.617021 (-1365 5);
PAINT ORANGE (-1365 5);
FORCEPROP 1 LAST PART_NUMBER 602433-106
J 0
(-1325 -225);
DISPLAY 0.617021 (-1325 -225);
PAINT BLUE (-1325 -225);
FORCEPROP 1 LAST PACK_TYPE 0603V
J 0
(-1325 -275);
DISPLAY 0.617021 (-1325 -275);
PAINT SKYBLUE (-1325 -275);
FORCEPROP 1 LAST MATERIAL X5R
J 0
(-1325 -175);
DISPLAY 0.617021 (-1325 -175);
PAINT SKYBLUE (-1325 -175);
FORCEPROP 1 LASTPIN (-1375 -175) $PN 2
J 0
(-1365 -195);
DISPLAY 0.617021 (-1365 -195);
PAINT ORANGE (-1365 -195);
FORCEPROP 1 LAST VALUE 47UF
J 0
(-1325 -25);
DISPLAY 0.617021 (-1325 -25);
PAINT SKYBLUE (-1325 -25);
FORCEPROP 1 LAST TOLERANCE 20%
J 0
(-1325 -125);
DISPLAY 0.617021 (-1325 -125);
PAINT SKYBLUE (-1325 -125);
FORCEPROP 1 LAST VOLTAGE 4V
J 0
(-1325 -75);
DISPLAY 0.617021 (-1325 -75);
PAINT SKYBLUE (-1325 -75);
FORCEPROP 0 LAST GROUP PWR_MLCC_CAP
J 0
(-1319 -488);
DISPLAY 0.638298 (-1319 -488);
PAINT BROWN (-1319 -488);
DISPLAY BOTH (-1319 -488);
FORCEPROP 1 LAST PATH I271
J 0
(-1325 75);
DISPLAY 0.978723 (-1325 75);
PAINT WHITE (-1325 75);
DISPLAY INVISIBLE (-1325 75);
FORCEPROP 2 LAST CDS_LIB dev_discrete
J 0
(-1375 -75);
PAINT ORANGE (-1375 -75);
DISPLAY INVISIBLE (-1375 -75);
FORCEPROP 2 LAST SEC 1
J 0
(-1325 125);
DISPLAY 0.680851 (-1325 125);
PAINT MONO (-1325 125);
DISPLAY INVISIBLE (-1325 125);
FORCEPROP 2 LAST SEC_TYPE 0603V
J 0
(-1325 125);
DISPLAY 1.021277 (-1325 125);
PAINT ORANGE (-1325 125);
DISPLAY INVISIBLE (-1325 125);
FORCEPROP 2 LAST CDS_SEC 1
J 0
(-1325 75);
PAINT ORANGE (-1325 75);
DISPLAY INVISIBLE (-1325 75);
FORCEPROP 2 LAST CDS_LOCATION C2A15
J 0
(-1325 25);
DISPLAY 0.617021 (-1325 25);
PAINT AQUA (-1325 25);
DISPLAY INVISIBLE (-1325 25);
FORCEADD CAP_A..1
(-1100 -75);
FORCEPROP 0 LAST BOM_SS E15431-004
J 0
(-1077 -349);
DISPLAY 0.510638 (-1077 -349);
PAINT BROWN (-1077 -349);
DISPLAY BOTH (-1077 -349);
FORCEPROP 1 LASTPIN (-1100 -175) $PN 2
J 0
(-1090 -195);
DISPLAY 0.617021 (-1090 -195);
PAINT ORANGE (-1090 -195);
FORCEPROP 1 LAST VOLTAGE 4V
J 0
(-1050 -75);
DISPLAY 0.617021 (-1050 -75);
PAINT SKYBLUE (-1050 -75);
FORCEPROP 1 LASTPIN (-1100 25) $PN 1
J 0
(-1090 5);
DISPLAY 0.617021 (-1090 5);
PAINT ORANGE (-1090 5);
FORCEPROP 1 LAST PACK_TYPE 0603V
J 0
(-1050 -275);
DISPLAY 0.617021 (-1050 -275);
PAINT SKYBLUE (-1050 -275);
FORCEPROP 1 LAST PART_NUMBER 602433-106
J 0
(-1050 -225);
DISPLAY 0.617021 (-1050 -225);
PAINT BLUE (-1050 -225);
FORCEPROP 1 LAST MATERIAL X5R
J 0
(-1050 -175);
DISPLAY 0.617021 (-1050 -175);
PAINT SKYBLUE (-1050 -175);
FORCEPROP 1 LAST TOLERANCE 20%
J 0
(-1050 -125);
DISPLAY 0.617021 (-1050 -125);
PAINT SKYBLUE (-1050 -125);
FORCEPROP 1 LAST VALUE 47UF
J 0
(-1050 -25);
DISPLAY 0.617021 (-1050 -25);
PAINT SKYBLUE (-1050 -25);
FORCEPROP 1 LAST LOCATION C2A14
J 0
(-1050 25);
DISPLAY 0.617021 (-1050 25);
PAINT AQUA (-1050 25);
FORCEPROP 0 LAST GROUP PWR_MLCC_CAP
J 0
(-1044 -438);
DISPLAY 0.638298 (-1044 -438);
PAINT BROWN (-1044 -438);
DISPLAY BOTH (-1044 -438);
FORCEPROP 1 LAST PATH I272
J 0
(-1050 75);
DISPLAY 0.978723 (-1050 75);
PAINT WHITE (-1050 75);
DISPLAY INVISIBLE (-1050 75);
FORCEPROP 2 LAST CDS_LIB dev_discrete
J 0
(-1100 -75);
PAINT ORANGE (-1100 -75);
DISPLAY INVISIBLE (-1100 -75);
FORCEPROP 2 LAST SEC 1
J 0
(-1050 125);
DISPLAY 0.680851 (-1050 125);
PAINT MONO (-1050 125);
DISPLAY INVISIBLE (-1050 125);
FORCEPROP 2 LAST SEC_TYPE 0603V
J 0
(-1050 125);
DISPLAY 1.021277 (-1050 125);
PAINT ORANGE (-1050 125);
DISPLAY INVISIBLE (-1050 125);
FORCEPROP 2 LAST CDS_SEC 1
J 0
(-1050 75);
PAINT ORANGE (-1050 75);
DISPLAY INVISIBLE (-1050 75);
FORCEPROP 2 LAST CDS_LOCATION C2A14
J 0
(-1050 25);
DISPLAY 0.617021 (-1050 25);
PAINT AQUA (-1050 25);
DISPLAY INVISIBLE (-1050 25);
FORCEADD CAP_A..1
(-800 -75);
FORCEPROP 0 LAST BOM_SS E15431-004
J 0
(-750 -392);
DISPLAY 0.510638 (-750 -392);
PAINT BROWN (-750 -392);
DISPLAY BOTH (-750 -392);
FORCEPROP 1 LASTPIN (-800 25) $PN 1
J 0
(-790 5);
DISPLAY 0.617021 (-790 5);
PAINT ORANGE (-790 5);
FORCEPROP 1 LASTPIN (-800 -175) $PN 2
J 0
(-790 -195);
DISPLAY 0.617021 (-790 -195);
PAINT ORANGE (-790 -195);
FORCEPROP 1 LAST MATERIAL X5R
J 0
(-750 -175);
DISPLAY 0.617021 (-750 -175);
PAINT SKYBLUE (-750 -175);
FORCEPROP 1 LAST VOLTAGE 4V
J 0
(-750 -75);
DISPLAY 0.617021 (-750 -75);
PAINT SKYBLUE (-750 -75);
FORCEPROP 1 LAST TOLERANCE 20%
J 0
(-750 -125);
DISPLAY 0.617021 (-750 -125);
PAINT SKYBLUE (-750 -125);
FORCEPROP 1 LAST PACK_TYPE 0603V
J 0
(-750 -275);
DISPLAY 0.617021 (-750 -275);
PAINT SKYBLUE (-750 -275);
FORCEPROP 1 LAST PART_NUMBER 602433-106
J 0
(-750 -225);
DISPLAY 0.617021 (-750 -225);
PAINT BLUE (-750 -225);
FORCEPROP 1 LAST VALUE 47UF
J 0
(-750 -25);
DISPLAY 0.617021 (-750 -25);
PAINT SKYBLUE (-750 -25);
FORCEPROP 1 LAST LOCATION C2A6
J 0
(-750 25);
DISPLAY 0.617021 (-750 25);
PAINT AQUA (-750 25);
FORCEPROP 0 LAST GROUP PWR_MLCC_CAP
J 0
(-744 -488);
DISPLAY 0.638298 (-744 -488);
PAINT BROWN (-744 -488);
DISPLAY BOTH (-744 -488);
FORCEPROP 2 LAST CDS_SEC 1
J 0
(-750 75);
PAINT ORANGE (-750 75);
DISPLAY INVISIBLE (-750 75);
FORCEPROP 2 LAST SEC_TYPE 0603V
J 0
(-750 125);
DISPLAY 1.021277 (-750 125);
PAINT ORANGE (-750 125);
DISPLAY INVISIBLE (-750 125);
FORCEPROP 2 LAST SEC 1
J 0
(-750 125);
DISPLAY 0.680851 (-750 125);
PAINT MONO (-750 125);
DISPLAY INVISIBLE (-750 125);
FORCEPROP 2 LAST CDS_LIB dev_discrete
J 0
(-800 -75);
PAINT ORANGE (-800 -75);
DISPLAY INVISIBLE (-800 -75);
FORCEPROP 1 LAST PATH I273
J 0
(-750 75);
DISPLAY 0.978723 (-750 75);
PAINT WHITE (-750 75);
DISPLAY INVISIBLE (-750 75);
FORCEPROP 2 LAST CDS_LOCATION C2A6
J 0
(-750 25);
DISPLAY 0.617021 (-750 25);
PAINT AQUA (-750 25);
DISPLAY INVISIBLE (-750 25);
FORCEADD CAP_A..1
(-500 -75);
FORCEPROP 0 LAST BOM_SS E15431-004
J 0
(-490 -338);
DISPLAY 0.510638 (-490 -338);
PAINT BROWN (-490 -338);
DISPLAY BOTH (-490 -338);
FORCEPROP 1 LAST PACK_TYPE 0603V
J 0
(-450 -275);
DISPLAY 0.617021 (-450 -275);
PAINT SKYBLUE (-450 -275);
FORCEPROP 1 LAST PART_NUMBER 602433-106
J 0
(-450 -225);
DISPLAY 0.617021 (-450 -225);
PAINT BLUE (-450 -225);
FORCEPROP 1 LAST VALUE 47UF
J 0
(-450 -25);
DISPLAY 0.617021 (-450 -25);
PAINT SKYBLUE (-450 -25);
FORCEPROP 1 LASTPIN (-500 25) $PN 1
J 0
(-490 5);
DISPLAY 0.617021 (-490 5);
PAINT ORANGE (-490 5);
FORCEPROP 1 LASTPIN (-500 -175) $PN 2
J 0
(-490 -195);
DISPLAY 0.617021 (-490 -195);
PAINT ORANGE (-490 -195);
FORCEPROP 1 LAST MATERIAL X5R
J 0
(-450 -175);
DISPLAY 0.617021 (-450 -175);
PAINT SKYBLUE (-450 -175);
FORCEPROP 1 LAST VOLTAGE 4V
J 0
(-450 -75);
DISPLAY 0.617021 (-450 -75);
PAINT SKYBLUE (-450 -75);
FORCEPROP 1 LAST TOLERANCE 20%
J 0
(-450 -125);
DISPLAY 0.617021 (-450 -125);
PAINT SKYBLUE (-450 -125);
FORCEPROP 1 LAST LOCATION C2A7
J 0
(-450 25);
DISPLAY 0.617021 (-450 25);
PAINT AQUA (-450 25);
FORCEPROP 0 LAST GROUP PWR_MLCC_CAP
J 0
(-444 -438);
DISPLAY 0.638298 (-444 -438);
PAINT BROWN (-444 -438);
DISPLAY BOTH (-444 -438);
FORCEPROP 2 LAST CDS_SEC 1
J 0
(-450 75);
PAINT ORANGE (-450 75);
DISPLAY INVISIBLE (-450 75);
FORCEPROP 2 LAST SEC_TYPE 0603V
J 0
(-450 125);
DISPLAY 1.021277 (-450 125);
PAINT ORANGE (-450 125);
DISPLAY INVISIBLE (-450 125);
FORCEPROP 2 LAST SEC 1
J 0
(-450 125);
DISPLAY 0.680851 (-450 125);
PAINT MONO (-450 125);
DISPLAY INVISIBLE (-450 125);
FORCEPROP 2 LAST CDS_LIB dev_discrete
J 0
(-500 -75);
PAINT ORANGE (-500 -75);
DISPLAY INVISIBLE (-500 -75);
FORCEPROP 1 LAST PATH I274
J 0
(-450 75);
DISPLAY 0.978723 (-450 75);
PAINT WHITE (-450 75);
DISPLAY INVISIBLE (-450 75);
FORCEPROP 2 LAST CDS_LOCATION C2A7
J 0
(-450 25);
DISPLAY 0.617021 (-450 25);
PAINT AQUA (-450 25);
DISPLAY INVISIBLE (-450 25);
FORCEADD CAP_A..1
(-225 -75);
FORCEPROP 0 LAST BOM_SS E15431-004
J 0
(-205 -392);
DISPLAY 0.510638 (-205 -392);
PAINT BROWN (-205 -392);
DISPLAY BOTH (-205 -392);
FORCEPROP 1 LAST PACK_TYPE 0603V
J 0
(-175 -275);
DISPLAY 0.617021 (-175 -275);
PAINT SKYBLUE (-175 -275);
FORCEPROP 1 LAST VALUE 47UF
J 0
(-175 -25);
DISPLAY 0.617021 (-175 -25);
PAINT SKYBLUE (-175 -25);
FORCEPROP 1 LASTPIN (-225 25) $PN 1
J 0
(-215 5);
DISPLAY 0.617021 (-215 5);
PAINT ORANGE (-215 5);
FORCEPROP 1 LASTPIN (-225 -175) $PN 2
J 0
(-215 -195);
DISPLAY 0.617021 (-215 -195);
PAINT ORANGE (-215 -195);
FORCEPROP 1 LAST MATERIAL X5R
J 0
(-175 -175);
DISPLAY 0.617021 (-175 -175);
PAINT SKYBLUE (-175 -175);
FORCEPROP 1 LAST LOCATION C3A1
J 0
(-175 25);
DISPLAY 0.617021 (-175 25);
PAINT AQUA (-175 25);
FORCEPROP 1 LAST VOLTAGE 4V
J 0
(-175 -75);
DISPLAY 0.617021 (-175 -75);
PAINT SKYBLUE (-175 -75);
FORCEPROP 1 LAST TOLERANCE 20%
J 0
(-175 -125);
DISPLAY 0.617021 (-175 -125);
PAINT SKYBLUE (-175 -125);
FORCEPROP 1 LAST PART_NUMBER 602433-106
J 0
(-175 -225);
DISPLAY 0.617021 (-175 -225);
PAINT BLUE (-175 -225);
FORCEPROP 0 LAST GROUP PWR_MLCC_CAP
J 0
(-194 -488);
DISPLAY 0.638298 (-194 -488);
PAINT BROWN (-194 -488);
DISPLAY BOTH (-194 -488);
FORCEPROP 2 LAST CDS_SEC 1
J 0
(-175 75);
PAINT ORANGE (-175 75);
DISPLAY INVISIBLE (-175 75);
FORCEPROP 2 LAST SEC_TYPE 0603V
J 0
(-175 125);
DISPLAY 1.021277 (-175 125);
PAINT ORANGE (-175 125);
DISPLAY INVISIBLE (-175 125);
FORCEPROP 2 LAST SEC 1
J 0
(-175 125);
DISPLAY 0.680851 (-175 125);
PAINT MONO (-175 125);
DISPLAY INVISIBLE (-175 125);
FORCEPROP 2 LAST CDS_LIB dev_discrete
J 0
(-225 -75);
PAINT ORANGE (-225 -75);
DISPLAY INVISIBLE (-225 -75);
FORCEPROP 1 LAST PATH I275
J 0
(-175 75);
DISPLAY 0.978723 (-175 75);
PAINT WHITE (-175 75);
DISPLAY INVISIBLE (-175 75);
FORCEPROP 2 LAST CDS_LOCATION C3A1
J 0
(-175 25);
DISPLAY 0.617021 (-175 25);
PAINT AQUA (-175 25);
DISPLAY INVISIBLE (-175 25);
FORCEADD CAP_A..1
(100 -75);
FORCEPROP 0 LAST BOM_SS E15431-004
J 0
(120 -331);
DISPLAY 0.510638 (120 -331);
PAINT BROWN (120 -331);
DISPLAY BOTH (120 -331);
FORCEPROP 1 LAST VALUE 47UF
J 0
(150 -25);
DISPLAY 0.617021 (150 -25);
PAINT SKYBLUE (150 -25);
FORCEPROP 1 LAST PACK_TYPE 0603V
J 0
(150 -275);
DISPLAY 0.617021 (150 -275);
PAINT SKYBLUE (150 -275);
FORCEPROP 1 LASTPIN (100 25) $PN 1
J 0
(110 5);
DISPLAY 0.617021 (110 5);
PAINT ORANGE (110 5);
FORCEPROP 1 LASTPIN (100 -175) $PN 2
J 0
(110 -195);
DISPLAY 0.617021 (110 -195);
PAINT ORANGE (110 -195);
FORCEPROP 1 LAST LOCATION C3A2
J 0
(150 25);
DISPLAY 0.617021 (150 25);
PAINT AQUA (150 25);
FORCEPROP 1 LAST VOLTAGE 4V
J 0
(150 -75);
DISPLAY 0.617021 (150 -75);
PAINT SKYBLUE (150 -75);
FORCEPROP 1 LAST TOLERANCE 20%
J 0
(150 -125);
DISPLAY 0.617021 (150 -125);
PAINT SKYBLUE (150 -125);
FORCEPROP 1 LAST MATERIAL X5R
J 0
(150 -175);
DISPLAY 0.617021 (150 -175);
PAINT SKYBLUE (150 -175);
FORCEPROP 1 LAST PART_NUMBER 602433-106
J 0
(150 -225);
DISPLAY 0.617021 (150 -225);
PAINT BLUE (150 -225);
FORCEPROP 0 LAST GROUP PWR_MLCC_CAP
J 0
(156 -438);
DISPLAY 0.638298 (156 -438);
PAINT BROWN (156 -438);
DISPLAY BOTH (156 -438);
FORCEPROP 2 LAST CDS_SEC 1
J 0
(150 75);
PAINT ORANGE (150 75);
DISPLAY INVISIBLE (150 75);
FORCEPROP 2 LAST SEC_TYPE 0603V
J 0
(150 125);
DISPLAY 1.021277 (150 125);
PAINT ORANGE (150 125);
DISPLAY INVISIBLE (150 125);
FORCEPROP 2 LAST SEC 1
J 0
(150 125);
DISPLAY 0.680851 (150 125);
PAINT MONO (150 125);
DISPLAY INVISIBLE (150 125);
FORCEPROP 2 LAST CDS_LIB dev_discrete
J 0
(100 -75);
PAINT ORANGE (100 -75);
DISPLAY INVISIBLE (100 -75);
FORCEPROP 1 LAST PATH I276
J 0
(150 75);
DISPLAY 0.978723 (150 75);
PAINT WHITE (150 75);
DISPLAY INVISIBLE (150 75);
FORCEPROP 2 LAST CDS_LOCATION C3A2
J 0
(150 25);
DISPLAY 0.617021 (150 25);
PAINT AQUA (150 25);
DISPLAY INVISIBLE (150 25);
FORCEADD CAP_A..1
(400 -75);
FORCEPROP 0 LAST BOM_SS E15431-004
J 0
(411 -398);
DISPLAY 0.510638 (411 -398);
PAINT BROWN (411 -398);
DISPLAY BOTH (411 -398);
FORCEPROP 1 LAST VOLTAGE 4V
J 0
(450 -75);
DISPLAY 0.617021 (450 -75);
PAINT SKYBLUE (450 -75);
FORCEPROP 1 LAST PART_NUMBER 602433-106
J 0
(450 -225);
DISPLAY 0.617021 (450 -225);
PAINT BLUE (450 -225);
FORCEPROP 1 LAST VALUE 47UF
J 0
(450 -25);
DISPLAY 0.617021 (450 -25);
PAINT SKYBLUE (450 -25);
FORCEPROP 1 LAST PACK_TYPE 0603V
J 0
(450 -275);
DISPLAY 0.617021 (450 -275);
PAINT SKYBLUE (450 -275);
FORCEPROP 1 LASTPIN (400 25) $PN 1
J 0
(410 5);
DISPLAY 0.617021 (410 5);
PAINT ORANGE (410 5);
FORCEPROP 1 LASTPIN (400 -175) $PN 2
J 0
(410 -195);
DISPLAY 0.617021 (410 -195);
PAINT ORANGE (410 -195);
FORCEPROP 1 LAST TOLERANCE 20%
J 0
(450 -125);
DISPLAY 0.617021 (450 -125);
PAINT SKYBLUE (450 -125);
FORCEPROP 1 LAST LOCATION C2A9
J 0
(450 25);
DISPLAY 0.617021 (450 25);
PAINT AQUA (450 25);
FORCEPROP 1 LAST MATERIAL X5R
J 0
(450 -175);
DISPLAY 0.617021 (450 -175);
PAINT SKYBLUE (450 -175);
FORCEPROP 0 LAST GROUP PWR_MLCC_CAP
J 0
(456 -488);
DISPLAY 0.638298 (456 -488);
PAINT BROWN (456 -488);
DISPLAY BOTH (456 -488);
FORCEPROP 2 LAST CDS_SEC 1
J 0
(450 75);
PAINT ORANGE (450 75);
DISPLAY INVISIBLE (450 75);
FORCEPROP 2 LAST SEC_TYPE 0603V
J 0
(450 125);
DISPLAY 1.021277 (450 125);
PAINT ORANGE (450 125);
DISPLAY INVISIBLE (450 125);
FORCEPROP 2 LAST SEC 1
J 0
(450 125);
DISPLAY 0.680851 (450 125);
PAINT MONO (450 125);
DISPLAY INVISIBLE (450 125);
FORCEPROP 2 LAST CDS_LIB dev_discrete
J 0
(400 -75);
PAINT ORANGE (400 -75);
DISPLAY INVISIBLE (400 -75);
FORCEPROP 1 LAST PATH I277
J 0
(450 75);
DISPLAY 0.978723 (450 75);
PAINT WHITE (450 75);
DISPLAY INVISIBLE (450 75);
FORCEPROP 2 LAST CDS_LOCATION C2A9
J 0
(450 25);
DISPLAY 0.617021 (450 25);
PAINT AQUA (450 25);
DISPLAY INVISIBLE (450 25);
FORCEADD CAP_A..1
(700 -75);
FORCEPROP 0 LAST BOM_SS E15431-004
J 0
(702 -330);
DISPLAY 0.510638 (702 -330);
PAINT BROWN (702 -330);
DISPLAY BOTH (702 -330);
FORCEPROP 1 LAST PACK_TYPE 0603V
J 0
(750 -275);
DISPLAY 0.617021 (750 -275);
PAINT SKYBLUE (750 -275);
FORCEPROP 1 LASTPIN (700 25) $PN 1
J 0
(710 5);
DISPLAY 0.617021 (710 5);
PAINT ORANGE (710 5);
FORCEPROP 1 LASTPIN (700 -175) $PN 2
J 0
(710 -195);
DISPLAY 0.617021 (710 -195);
PAINT ORANGE (710 -195);
FORCEPROP 1 LAST LOCATION C2A10
J 0
(750 25);
DISPLAY 0.617021 (750 25);
PAINT AQUA (750 25);
FORCEPROP 1 LAST VOLTAGE 4V
J 0
(750 -75);
DISPLAY 0.617021 (750 -75);
PAINT SKYBLUE (750 -75);
FORCEPROP 1 LAST VALUE 47UF
J 0
(750 -25);
DISPLAY 0.617021 (750 -25);
PAINT SKYBLUE (750 -25);
FORCEPROP 1 LAST TOLERANCE 20%
J 0
(750 -125);
DISPLAY 0.617021 (750 -125);
PAINT SKYBLUE (750 -125);
FORCEPROP 1 LAST PART_NUMBER 602433-106
J 0
(750 -225);
DISPLAY 0.617021 (750 -225);
PAINT BLUE (750 -225);
FORCEPROP 1 LAST MATERIAL X5R
J 0
(750 -175);
DISPLAY 0.617021 (750 -175);
PAINT SKYBLUE (750 -175);
FORCEPROP 0 LAST GROUP PWR_MLCC_CAP
J 0
(731 -438);
DISPLAY 0.638298 (731 -438);
PAINT BROWN (731 -438);
DISPLAY BOTH (731 -438);
FORCEPROP 2 LAST CDS_SEC 1
J 0
(750 75);
PAINT ORANGE (750 75);
DISPLAY INVISIBLE (750 75);
FORCEPROP 2 LAST SEC_TYPE 0603V
J 0
(750 125);
DISPLAY 1.021277 (750 125);
PAINT ORANGE (750 125);
DISPLAY INVISIBLE (750 125);
FORCEPROP 2 LAST SEC 1
J 0
(750 125);
DISPLAY 0.680851 (750 125);
PAINT MONO (750 125);
DISPLAY INVISIBLE (750 125);
FORCEPROP 2 LAST CDS_LIB dev_discrete
J 0
(700 -75);
PAINT ORANGE (700 -75);
DISPLAY INVISIBLE (700 -75);
FORCEPROP 1 LAST PATH I278
J 0
(750 75);
DISPLAY 0.978723 (750 75);
PAINT WHITE (750 75);
DISPLAY INVISIBLE (750 75);
FORCEPROP 2 LAST CDS_LOCATION C2A10
J 0
(750 25);
DISPLAY 0.617021 (750 25);
PAINT AQUA (750 25);
DISPLAY INVISIBLE (750 25);
FORCEADD CAP_A..1
(975 -75);
FORCEPROP 0 LAST BOM_SS E15431-004
J 0
(994 -381);
DISPLAY 0.510638 (994 -381);
PAINT BROWN (994 -381);
DISPLAY BOTH (994 -381);
FORCEPROP 1 LAST PACK_TYPE 0603V
J 0
(1025 -275);
DISPLAY 0.617021 (1025 -275);
PAINT SKYBLUE (1025 -275);
FORCEPROP 1 LASTPIN (975 25) $PN 1
J 0
(985 5);
DISPLAY 0.617021 (985 5);
PAINT ORANGE (985 5);
FORCEPROP 1 LASTPIN (975 -175) $PN 2
J 0
(985 -195);
DISPLAY 0.617021 (985 -195);
PAINT ORANGE (985 -195);
FORCEPROP 1 LAST MATERIAL X5R
J 0
(1025 -175);
DISPLAY 0.617021 (1025 -175);
PAINT SKYBLUE (1025 -175);
FORCEPROP 1 LAST LOCATION C2A11
J 0
(1025 25);
DISPLAY 0.617021 (1025 25);
PAINT AQUA (1025 25);
FORCEPROP 1 LAST VOLTAGE 4V
J 0
(1025 -75);
DISPLAY 0.617021 (1025 -75);
PAINT SKYBLUE (1025 -75);
FORCEPROP 1 LAST VALUE 47UF
J 0
(1025 -25);
DISPLAY 0.617021 (1025 -25);
PAINT SKYBLUE (1025 -25);
FORCEPROP 1 LAST TOLERANCE 20%
J 0
(1025 -125);
DISPLAY 0.617021 (1025 -125);
PAINT SKYBLUE (1025 -125);
FORCEPROP 1 LAST PART_NUMBER 602433-106
J 0
(1025 -225);
DISPLAY 0.617021 (1025 -225);
PAINT BLUE (1025 -225);
FORCEPROP 0 LAST GROUP PWR_MLCC_CAP
J 0
(1031 -488);
DISPLAY 0.638298 (1031 -488);
PAINT BROWN (1031 -488);
DISPLAY BOTH (1031 -488);
FORCEPROP 2 LAST CDS_SEC 1
J 0
(1025 75);
PAINT ORANGE (1025 75);
DISPLAY INVISIBLE (1025 75);
FORCEPROP 2 LAST SEC_TYPE 0603V
J 0
(1025 125);
DISPLAY 1.021277 (1025 125);
PAINT ORANGE (1025 125);
DISPLAY INVISIBLE (1025 125);
FORCEPROP 2 LAST SEC 1
J 0
(1025 125);
DISPLAY 0.680851 (1025 125);
PAINT MONO (1025 125);
DISPLAY INVISIBLE (1025 125);
FORCEPROP 2 LAST CDS_LIB dev_discrete
J 0
(975 -75);
PAINT ORANGE (975 -75);
DISPLAY INVISIBLE (975 -75);
FORCEPROP 1 LAST PATH I279
J 0
(1025 75);
DISPLAY 0.978723 (1025 75);
PAINT WHITE (1025 75);
DISPLAY INVISIBLE (1025 75);
FORCEPROP 2 LAST CDS_LOCATION C2A11
J 0
(1025 25);
DISPLAY 0.617021 (1025 25);
PAINT AQUA (1025 25);
DISPLAY INVISIBLE (1025 25);
FORCEADD CAP_A..1
(1250 -75);
FORCEPROP 0 LAST BOM_SS E15431-004
J 0
(1275 -348);
DISPLAY 0.510638 (1275 -348);
PAINT BROWN (1275 -348);
DISPLAY BOTH (1275 -348);
FORCEPROP 1 LAST MATERIAL X5R
J 0
(1300 -175);
DISPLAY 0.617021 (1300 -175);
PAINT SKYBLUE (1300 -175);
FORCEPROP 1 LASTPIN (1250 -175) $PN 2
J 0
(1260 -195);
DISPLAY 0.617021 (1260 -195);
PAINT ORANGE (1260 -195);
FORCEPROP 1 LASTPIN (1250 25) $PN 1
J 0
(1260 5);
DISPLAY 0.617021 (1260 5);
PAINT ORANGE (1260 5);
FORCEPROP 1 LAST PART_NUMBER 602433-106
J 0
(1300 -225);
DISPLAY 0.617021 (1300 -225);
PAINT BLUE (1300 -225);
FORCEPROP 1 LAST LOCATION C2A13
J 0
(1300 25);
DISPLAY 0.617021 (1300 25);
PAINT AQUA (1300 25);
FORCEPROP 1 LAST TOLERANCE 20%
J 0
(1300 -125);
DISPLAY 0.617021 (1300 -125);
PAINT SKYBLUE (1300 -125);
FORCEPROP 1 LAST VALUE 47UF
J 0
(1300 -25);
DISPLAY 0.617021 (1300 -25);
PAINT SKYBLUE (1300 -25);
FORCEPROP 1 LAST VOLTAGE 4V
J 0
(1300 -75);
DISPLAY 0.617021 (1300 -75);
PAINT SKYBLUE (1300 -75);
FORCEPROP 1 LAST PACK_TYPE 0603V
J 0
(1300 -275);
DISPLAY 0.617021 (1300 -275);
PAINT SKYBLUE (1300 -275);
FORCEPROP 0 LAST GROUP PWR_MLCC_CAP
J 0
(1281 -438);
DISPLAY 0.638298 (1281 -438);
PAINT BROWN (1281 -438);
DISPLAY BOTH (1281 -438);
FORCEPROP 1 LAST PATH I280
J 0
(1300 75);
DISPLAY 0.978723 (1300 75);
PAINT WHITE (1300 75);
DISPLAY INVISIBLE (1300 75);
FORCEPROP 2 LAST CDS_LIB dev_discrete
J 0
(1250 -75);
PAINT ORANGE (1250 -75);
DISPLAY INVISIBLE (1250 -75);
FORCEPROP 2 LAST SEC 1
J 0
(1300 125);
DISPLAY 0.680851 (1300 125);
PAINT MONO (1300 125);
DISPLAY INVISIBLE (1300 125);
FORCEPROP 2 LAST SEC_TYPE 0603V
J 0
(1300 125);
DISPLAY 1.021277 (1300 125);
PAINT ORANGE (1300 125);
DISPLAY INVISIBLE (1300 125);
FORCEPROP 2 LAST CDS_SEC 1
J 0
(1300 75);
PAINT ORANGE (1300 75);
DISPLAY INVISIBLE (1300 75);
FORCEPROP 2 LAST CDS_LOCATION C2A13
J 0
(1300 25);
DISPLAY 0.617021 (1300 25);
PAINT AQUA (1300 25);
DISPLAY INVISIBLE (1300 25);
FORCEADD CAP_A..1
(1550 -75);
FORCEPROP 0 LAST BOM_SS E15431-004
J 0
(1582 -400);
DISPLAY 0.510638 (1582 -400);
PAINT BROWN (1582 -400);
DISPLAY BOTH (1582 -400);
FORCEPROP 1 LAST LOCATION C2A12
J 0
(1600 25);
DISPLAY 0.617021 (1600 25);
PAINT AQUA (1600 25);
FORCEPROP 1 LAST PART_NUMBER 602433-106
J 0
(1600 -225);
DISPLAY 0.617021 (1600 -225);
PAINT BLUE (1600 -225);
FORCEPROP 1 LAST PACK_TYPE 0603V
J 0
(1600 -275);
DISPLAY 0.617021 (1600 -275);
PAINT SKYBLUE (1600 -275);
FORCEPROP 1 LAST MATERIAL X5R
J 0
(1600 -175);
DISPLAY 0.617021 (1600 -175);
PAINT SKYBLUE (1600 -175);
FORCEPROP 1 LASTPIN (1550 -175) $PN 2
J 0
(1560 -195);
DISPLAY 0.617021 (1560 -195);
PAINT ORANGE (1560 -195);
FORCEPROP 1 LASTPIN (1550 25) $PN 1
J 0
(1560 5);
DISPLAY 0.617021 (1560 5);
PAINT ORANGE (1560 5);
FORCEPROP 1 LAST TOLERANCE 20%
J 0
(1600 -125);
DISPLAY 0.617021 (1600 -125);
PAINT SKYBLUE (1600 -125);
FORCEPROP 1 LAST VOLTAGE 4V
J 0
(1600 -75);
DISPLAY 0.617021 (1600 -75);
PAINT SKYBLUE (1600 -75);
FORCEPROP 1 LAST VALUE 47UF
J 0
(1600 -25);
DISPLAY 0.617021 (1600 -25);
PAINT SKYBLUE (1600 -25);
FORCEPROP 0 LAST GROUP PWR_MLCC_CAP
J 0
(1606 -488);
DISPLAY 0.638298 (1606 -488);
PAINT BROWN (1606 -488);
DISPLAY BOTH (1606 -488);
FORCEPROP 1 LAST PATH I281
J 0
(1600 75);
DISPLAY 0.978723 (1600 75);
PAINT WHITE (1600 75);
DISPLAY INVISIBLE (1600 75);
FORCEPROP 2 LAST CDS_LIB dev_discrete
J 0
(1550 -75);
PAINT ORANGE (1550 -75);
DISPLAY INVISIBLE (1550 -75);
FORCEPROP 2 LAST SEC 1
J 0
(1600 125);
DISPLAY 0.680851 (1600 125);
PAINT MONO (1600 125);
DISPLAY INVISIBLE (1600 125);
FORCEPROP 2 LAST SEC_TYPE 0603V
J 0
(1600 125);
DISPLAY 1.021277 (1600 125);
PAINT ORANGE (1600 125);
DISPLAY INVISIBLE (1600 125);
FORCEPROP 2 LAST CDS_SEC 1
J 0
(1600 75);
PAINT ORANGE (1600 75);
DISPLAY INVISIBLE (1600 75);
FORCEPROP 2 LAST CDS_LOCATION C2A12
J 0
(1600 25);
DISPLAY 0.617021 (1600 25);
PAINT AQUA (1600 25);
DISPLAY INVISIBLE (1600 25);
FORCEADD CAP_A..1
(1850 -75);
FORCEPROP 0 LAST BOM_SS E15431-004
J 0
(1861 -339);
DISPLAY 0.510638 (1861 -339);
PAINT BROWN (1861 -339);
DISPLAY BOTH (1861 -339);
FORCEPROP 1 LASTPIN (1850 25) $PN 1
J 0
(1860 5);
DISPLAY 0.617021 (1860 5);
PAINT ORANGE (1860 5);
FORCEPROP 1 LASTPIN (1850 -175) $PN 2
J 0
(1860 -195);
DISPLAY 0.617021 (1860 -195);
PAINT ORANGE (1860 -195);
FORCEPROP 1 LAST MATERIAL X5R
J 0
(1900 -175);
DISPLAY 0.617021 (1900 -175);
PAINT SKYBLUE (1900 -175);
FORCEPROP 1 LAST VALUE 47UF
J 0
(1900 -25);
DISPLAY 0.617021 (1900 -25);
PAINT SKYBLUE (1900 -25);
FORCEPROP 1 LAST TOLERANCE 20%
J 0
(1900 -125);
DISPLAY 0.617021 (1900 -125);
PAINT SKYBLUE (1900 -125);
FORCEPROP 1 LAST PART_NUMBER 602433-106
J 0
(1900 -225);
DISPLAY 0.617021 (1900 -225);
PAINT BLUE (1900 -225);
FORCEPROP 1 LAST PACK_TYPE 0603V
J 0
(1900 -275);
DISPLAY 0.617021 (1900 -275);
PAINT SKYBLUE (1900 -275);
FORCEPROP 1 LAST LOCATION C2A1
J 0
(1900 25);
DISPLAY 0.617021 (1900 25);
PAINT AQUA (1900 25);
FORCEPROP 1 LAST VOLTAGE 4V
J 0
(1900 -75);
DISPLAY 0.617021 (1900 -75);
PAINT SKYBLUE (1900 -75);
FORCEPROP 0 LAST GROUP PWR_MLCC_CAP
J 0
(1881 -438);
DISPLAY 0.638298 (1881 -438);
PAINT BROWN (1881 -438);
DISPLAY BOTH (1881 -438);
FORCEPROP 2 LAST CDS_SEC 1
J 0
(1900 75);
PAINT ORANGE (1900 75);
DISPLAY INVISIBLE (1900 75);
FORCEPROP 2 LAST SEC_TYPE 0603V
J 0
(1900 125);
DISPLAY 1.021277 (1900 125);
PAINT ORANGE (1900 125);
DISPLAY INVISIBLE (1900 125);
FORCEPROP 2 LAST SEC 1
J 0
(1900 125);
DISPLAY 0.680851 (1900 125);
PAINT MONO (1900 125);
DISPLAY INVISIBLE (1900 125);
FORCEPROP 2 LAST CDS_LIB dev_discrete
J 0
(1850 -75);
PAINT ORANGE (1850 -75);
DISPLAY INVISIBLE (1850 -75);
FORCEPROP 1 LAST PATH I282
J 0
(1900 75);
DISPLAY 0.978723 (1900 75);
PAINT WHITE (1900 75);
DISPLAY INVISIBLE (1900 75);
FORCEPROP 2 LAST CDS_LOCATION C2A1
J 0
(1900 25);
DISPLAY 0.617021 (1900 25);
PAINT AQUA (1900 25);
DISPLAY INVISIBLE (1900 25);
FORCEADD CAP_A..1
(2125 -75);
FORCEPROP 0 LAST BOM_SS E15431-004
J 0
(2135 -389);
DISPLAY 0.510638 (2135 -389);
PAINT BROWN (2135 -389);
DISPLAY BOTH (2135 -389);
FORCEPROP 1 LASTPIN (2125 -175) $PN 2
J 0
(2135 -195);
DISPLAY 0.617021 (2135 -195);
PAINT ORANGE (2135 -195);
FORCEPROP 1 LASTPIN (2125 25) $PN 1
J 0
(2135 5);
DISPLAY 0.617021 (2135 5);
PAINT ORANGE (2135 5);
FORCEPROP 1 LAST VALUE 47UF
J 0
(2175 -25);
DISPLAY 0.617021 (2175 -25);
PAINT SKYBLUE (2175 -25);
FORCEPROP 1 LAST VOLTAGE 4V
J 0
(2175 -75);
DISPLAY 0.617021 (2175 -75);
PAINT SKYBLUE (2175 -75);
FORCEPROP 1 LAST LOCATION C2A2
J 0
(2175 25);
DISPLAY 0.617021 (2175 25);
PAINT AQUA (2175 25);
FORCEPROP 1 LAST PART_NUMBER 602433-106
J 0
(2175 -225);
DISPLAY 0.617021 (2175 -225);
PAINT BLUE (2175 -225);
FORCEPROP 1 LAST TOLERANCE 20%
J 0
(2175 -125);
DISPLAY 0.617021 (2175 -125);
PAINT SKYBLUE (2175 -125);
FORCEPROP 1 LAST MATERIAL X5R
J 0
(2175 -175);
DISPLAY 0.617021 (2175 -175);
PAINT SKYBLUE (2175 -175);
FORCEPROP 1 LAST PACK_TYPE 0603V
J 0
(2175 -275);
DISPLAY 0.617021 (2175 -275);
PAINT SKYBLUE (2175 -275);
FORCEPROP 0 LAST GROUP PWR_MLCC_CAP
J 0
(2156 -488);
DISPLAY 0.638298 (2156 -488);
PAINT BROWN (2156 -488);
DISPLAY BOTH (2156 -488);
FORCEPROP 1 LAST PATH I283
J 0
(2175 75);
DISPLAY 0.978723 (2175 75);
PAINT WHITE (2175 75);
DISPLAY INVISIBLE (2175 75);
FORCEPROP 2 LAST CDS_LIB dev_discrete
J 0
(2125 -75);
PAINT ORANGE (2125 -75);
DISPLAY INVISIBLE (2125 -75);
FORCEPROP 2 LAST SEC 1
J 0
(2175 125);
DISPLAY 0.680851 (2175 125);
PAINT MONO (2175 125);
DISPLAY INVISIBLE (2175 125);
FORCEPROP 2 LAST SEC_TYPE 0603V
J 0
(2175 125);
DISPLAY 1.021277 (2175 125);
PAINT ORANGE (2175 125);
DISPLAY INVISIBLE (2175 125);
FORCEPROP 2 LAST CDS_SEC 1
J 0
(2175 75);
PAINT ORANGE (2175 75);
DISPLAY INVISIBLE (2175 75);
FORCEPROP 2 LAST CDS_LOCATION C2A2
J 0
(2175 25);
DISPLAY 0.617021 (2175 25);
PAINT AQUA (2175 25);
DISPLAY INVISIBLE (2175 25);
FORCEADD CAP_A..1
(-2225 -775);
FORCEPROP 0 LAST BOM_SS E15431-004
J 0
(-2174 -1061);
DISPLAY 0.510638 (-2174 -1061);
PAINT BROWN (-2174 -1061);
DISPLAY BOTH (-2174 -1061);
FORCEPROP 1 LAST PART_NUMBER 602433-106
J 0
(-2175 -925);
DISPLAY 0.617021 (-2175 -925);
PAINT BLUE (-2175 -925);
FORCEPROP 1 LAST PACK_TYPE 0603V
J 0
(-2175 -975);
DISPLAY 0.617021 (-2175 -975);
PAINT SKYBLUE (-2175 -975);
FORCEPROP 1 LASTPIN (-2225 -675) $PN 1
J 0
(-2215 -695);
DISPLAY 0.617021 (-2215 -695);
PAINT ORANGE (-2215 -695);
FORCEPROP 1 LASTPIN (-2225 -875) $PN 2
J 0
(-2215 -895);
DISPLAY 0.617021 (-2215 -895);
PAINT ORANGE (-2215 -895);
FORCEPROP 1 LAST MATERIAL X5R
J 0
(-2175 -875);
DISPLAY 0.617021 (-2175 -875);
PAINT SKYBLUE (-2175 -875);
FORCEPROP 1 LAST LOCATION C8M1
J 0
(-2175 -675);
DISPLAY 0.617021 (-2175 -675);
PAINT AQUA (-2175 -675);
FORCEPROP 1 LAST TOLERANCE 20%
J 0
(-2175 -825);
DISPLAY 0.617021 (-2175 -825);
PAINT SKYBLUE (-2175 -825);
FORCEPROP 1 LAST VALUE 47UF
J 0
(-2175 -725);
DISPLAY 0.617021 (-2175 -725);
PAINT SKYBLUE (-2175 -725);
FORCEPROP 1 LAST VOLTAGE 4V
J 0
(-2175 -775);
DISPLAY 0.617021 (-2175 -775);
PAINT SKYBLUE (-2175 -775);
FORCEPROP 0 LAST GROUP PWR_MLCC_CAP
J 0
(-2169 -1013);
DISPLAY 0.638298 (-2169 -1013);
PAINT BROWN (-2169 -1013);
DISPLAY BOTH (-2169 -1013);
FORCEPROP 2 LAST CDS_SEC 1
J 0
(-2175 -625);
PAINT ORANGE (-2175 -625);
DISPLAY INVISIBLE (-2175 -625);
FORCEPROP 2 LAST SEC_TYPE 0603V
J 0
(-2175 -575);
DISPLAY 1.021277 (-2175 -575);
PAINT ORANGE (-2175 -575);
DISPLAY INVISIBLE (-2175 -575);
FORCEPROP 2 LAST SEC 1
J 0
(-2175 -575);
DISPLAY 0.680851 (-2175 -575);
PAINT MONO (-2175 -575);
DISPLAY INVISIBLE (-2175 -575);
FORCEPROP 2 LAST CDS_LIB dev_discrete
J 0
(-2225 -775);
PAINT ORANGE (-2225 -775);
DISPLAY INVISIBLE (-2225 -775);
FORCEPROP 1 LAST PATH I284
J 0
(-2175 -625);
DISPLAY 0.978723 (-2175 -625);
PAINT WHITE (-2175 -625);
DISPLAY INVISIBLE (-2175 -625);
FORCEPROP 2 LAST CDS_LOCATION C8M1
J 0
(-2175 -675);
DISPLAY 0.617021 (-2175 -675);
PAINT AQUA (-2175 -675);
DISPLAY INVISIBLE (-2175 -675);
FORCEADD CAP_A..1
(-1925 -775);
FORCEPROP 0 LAST BOM_SS E15431-004
J 0
(-1878 -1084);
DISPLAY 0.510638 (-1878 -1084);
PAINT BROWN (-1878 -1084);
DISPLAY BOTH (-1878 -1084);
FORCEPROP 1 LAST MATERIAL X5R
J 0
(-1875 -875);
DISPLAY 0.617021 (-1875 -875);
PAINT SKYBLUE (-1875 -875);
FORCEPROP 1 LASTPIN (-1925 -875) $PN 2
J 0
(-1915 -895);
DISPLAY 0.617021 (-1915 -895);
PAINT ORANGE (-1915 -895);
FORCEPROP 1 LAST PACK_TYPE 0603V
J 0
(-1875 -975);
DISPLAY 0.617021 (-1875 -975);
PAINT SKYBLUE (-1875 -975);
FORCEPROP 1 LAST PART_NUMBER 602433-106
J 0
(-1875 -925);
DISPLAY 0.617021 (-1875 -925);
PAINT BLUE (-1875 -925);
FORCEPROP 1 LAST TOLERANCE 20%
J 0
(-1875 -825);
DISPLAY 0.617021 (-1875 -825);
PAINT SKYBLUE (-1875 -825);
FORCEPROP 1 LAST VOLTAGE 4V
J 0
(-1875 -775);
DISPLAY 0.617021 (-1875 -775);
PAINT SKYBLUE (-1875 -775);
FORCEPROP 1 LAST VALUE 47UF
J 0
(-1875 -725);
DISPLAY 0.617021 (-1875 -725);
PAINT SKYBLUE (-1875 -725);
FORCEPROP 1 LASTPIN (-1925 -675) $PN 1
J 0
(-1915 -695);
DISPLAY 0.617021 (-1915 -695);
PAINT ORANGE (-1915 -695);
FORCEPROP 1 LAST LOCATION C8L5
J 0
(-1875 -675);
DISPLAY 0.617021 (-1875 -675);
PAINT AQUA (-1875 -675);
FORCEPROP 0 LAST GROUP PWR_MLCC_CAP
J 0
(-1869 -1163);
DISPLAY 0.638298 (-1869 -1163);
PAINT BROWN (-1869 -1163);
DISPLAY BOTH (-1869 -1163);
FORCEPROP 2 LAST CDS_LIB dev_discrete
J 0
(-1925 -775);
PAINT ORANGE (-1925 -775);
DISPLAY INVISIBLE (-1925 -775);
FORCEPROP 2 LAST SEC 1
J 0
(-1875 -575);
DISPLAY 0.680851 (-1875 -575);
PAINT MONO (-1875 -575);
DISPLAY INVISIBLE (-1875 -575);
FORCEPROP 2 LAST SEC_TYPE 0603V
J 0
(-1875 -575);
DISPLAY 1.021277 (-1875 -575);
PAINT ORANGE (-1875 -575);
DISPLAY INVISIBLE (-1875 -575);
FORCEPROP 2 LAST CDS_SEC 1
J 0
(-1875 -625);
PAINT ORANGE (-1875 -625);
DISPLAY INVISIBLE (-1875 -625);
FORCEPROP 1 LAST PATH I285
J 0
(-1875 -625);
DISPLAY 0.978723 (-1875 -625);
PAINT WHITE (-1875 -625);
DISPLAY INVISIBLE (-1875 -625);
FORCEPROP 2 LAST CDS_LOCATION C8L5
J 0
(-1875 -675);
DISPLAY 0.617021 (-1875 -675);
PAINT AQUA (-1875 -675);
DISPLAY INVISIBLE (-1875 -675);
FORCEADD CAP_A..1
(-1625 -775);
FORCEPROP 0 LAST BOM_SS E15431-004
J 0
(-1592 -1033);
DISPLAY 0.510638 (-1592 -1033);
PAINT BROWN (-1592 -1033);
DISPLAY BOTH (-1592 -1033);
FORCEPROP 1 LASTPIN (-1625 -675) $PN 1
J 0
(-1615 -695);
DISPLAY 0.617021 (-1615 -695);
PAINT ORANGE (-1615 -695);
FORCEPROP 1 LAST LOCATION C8L6
J 0
(-1575 -675);
DISPLAY 0.617021 (-1575 -675);
PAINT AQUA (-1575 -675);
FORCEPROP 1 LAST VALUE 47UF
J 0
(-1575 -725);
DISPLAY 0.617021 (-1575 -725);
PAINT SKYBLUE (-1575 -725);
FORCEPROP 1 LASTPIN (-1625 -875) $PN 2
J 0
(-1615 -895);
DISPLAY 0.617021 (-1615 -895);
PAINT ORANGE (-1615 -895);
FORCEPROP 1 LAST MATERIAL X5R
J 0
(-1575 -875);
DISPLAY 0.617021 (-1575 -875);
PAINT SKYBLUE (-1575 -875);
FORCEPROP 1 LAST PART_NUMBER 602433-106
J 0
(-1575 -925);
DISPLAY 0.617021 (-1575 -925);
PAINT BLUE (-1575 -925);
FORCEPROP 1 LAST VOLTAGE 4V
J 0
(-1575 -775);
DISPLAY 0.617021 (-1575 -775);
PAINT SKYBLUE (-1575 -775);
FORCEPROP 1 LAST PACK_TYPE 0603V
J 0
(-1575 -975);
DISPLAY 0.617021 (-1575 -975);
PAINT SKYBLUE (-1575 -975);
FORCEPROP 1 LAST TOLERANCE 20%
J 0
(-1575 -825);
DISPLAY 0.617021 (-1575 -825);
PAINT SKYBLUE (-1575 -825);
FORCEPROP 0 LAST GROUP PWR_MLCC_CAP
J 0
(-1569 -1013);
DISPLAY 0.638298 (-1569 -1013);
PAINT BROWN (-1569 -1013);
DISPLAY BOTH (-1569 -1013);
FORCEPROP 2 LAST CDS_SEC 1
J 0
(-1575 -625);
PAINT ORANGE (-1575 -625);
DISPLAY INVISIBLE (-1575 -625);
FORCEPROP 2 LAST SEC_TYPE 0603V
J 0
(-1575 -575);
DISPLAY 1.021277 (-1575 -575);
PAINT ORANGE (-1575 -575);
DISPLAY INVISIBLE (-1575 -575);
FORCEPROP 2 LAST SEC 1
J 0
(-1575 -575);
DISPLAY 0.680851 (-1575 -575);
PAINT MONO (-1575 -575);
DISPLAY INVISIBLE (-1575 -575);
FORCEPROP 2 LAST CDS_LIB dev_discrete
J 0
(-1625 -775);
PAINT ORANGE (-1625 -775);
DISPLAY INVISIBLE (-1625 -775);
FORCEPROP 1 LAST PATH I286
J 0
(-1575 -625);
DISPLAY 0.978723 (-1575 -625);
PAINT WHITE (-1575 -625);
DISPLAY INVISIBLE (-1575 -625);
FORCEPROP 2 LAST CDS_LOCATION C8L6
J 0
(-1575 -675);
DISPLAY 0.617021 (-1575 -675);
PAINT AQUA (-1575 -675);
DISPLAY INVISIBLE (-1575 -675);
FORCEADD CAP_A..1
(-1350 -775);
FORCEPROP 0 LAST BOM_SS E15431-004
J 0
(-1324 -1089);
DISPLAY 0.510638 (-1324 -1089);
PAINT BROWN (-1324 -1089);
DISPLAY BOTH (-1324 -1089);
FORCEPROP 1 LAST PART_NUMBER 602433-106
J 0
(-1300 -925);
DISPLAY 0.617021 (-1300 -925);
PAINT BLUE (-1300 -925);
FORCEPROP 1 LAST VOLTAGE 4V
J 0
(-1300 -775);
DISPLAY 0.617021 (-1300 -775);
PAINT SKYBLUE (-1300 -775);
FORCEPROP 1 LAST MATERIAL X5R
J 0
(-1300 -875);
DISPLAY 0.617021 (-1300 -875);
PAINT SKYBLUE (-1300 -875);
FORCEPROP 1 LASTPIN (-1350 -875) $PN 2
J 0
(-1340 -895);
DISPLAY 0.617021 (-1340 -895);
PAINT ORANGE (-1340 -895);
FORCEPROP 1 LASTPIN (-1350 -675) $PN 1
J 0
(-1340 -695);
DISPLAY 0.617021 (-1340 -695);
PAINT ORANGE (-1340 -695);
FORCEPROP 1 LAST PACK_TYPE 0603V
J 0
(-1300 -975);
DISPLAY 0.617021 (-1300 -975);
PAINT SKYBLUE (-1300 -975);
FORCEPROP 1 LAST VALUE 47UF
J 0
(-1300 -725);
DISPLAY 0.617021 (-1300 -725);
PAINT SKYBLUE (-1300 -725);
FORCEPROP 1 LAST LOCATION C8L7
J 0
(-1300 -675);
DISPLAY 0.617021 (-1300 -675);
PAINT AQUA (-1300 -675);
FORCEPROP 1 LAST TOLERANCE 20%
J 0
(-1300 -825);
DISPLAY 0.617021 (-1300 -825);
PAINT SKYBLUE (-1300 -825);
FORCEPROP 0 LAST GROUP PWR_MLCC_CAP
J 0
(-1294 -1188);
DISPLAY 0.638298 (-1294 -1188);
PAINT BROWN (-1294 -1188);
DISPLAY BOTH (-1294 -1188);
FORCEPROP 2 LAST CDS_LIB dev_discrete
J 0
(-1350 -775);
PAINT ORANGE (-1350 -775);
DISPLAY INVISIBLE (-1350 -775);
FORCEPROP 2 LAST SEC 1
J 0
(-1300 -575);
DISPLAY 0.680851 (-1300 -575);
PAINT MONO (-1300 -575);
DISPLAY INVISIBLE (-1300 -575);
FORCEPROP 2 LAST SEC_TYPE 0603V
J 0
(-1300 -575);
DISPLAY 1.021277 (-1300 -575);
PAINT ORANGE (-1300 -575);
DISPLAY INVISIBLE (-1300 -575);
FORCEPROP 2 LAST CDS_SEC 1
J 0
(-1300 -625);
PAINT ORANGE (-1300 -625);
DISPLAY INVISIBLE (-1300 -625);
FORCEPROP 1 LAST PATH I287
J 0
(-1300 -625);
DISPLAY 0.978723 (-1300 -625);
PAINT WHITE (-1300 -625);
DISPLAY INVISIBLE (-1300 -625);
FORCEPROP 2 LAST CDS_LOCATION C8L7
J 0
(-1300 -675);
DISPLAY 0.617021 (-1300 -675);
PAINT AQUA (-1300 -675);
DISPLAY INVISIBLE (-1300 -675);
FORCEADD CAP_A..1
(-1075 -775);
FORCEPROP 0 LAST BOM_SS E15431-004
J 0
(-1037 -1046);
DISPLAY 0.510638 (-1037 -1046);
PAINT BROWN (-1037 -1046);
DISPLAY BOTH (-1037 -1046);
FORCEPROP 1 LAST LOCATION C7L4
J 0
(-1025 -675);
DISPLAY 0.617021 (-1025 -675);
PAINT AQUA (-1025 -675);
FORCEPROP 1 LAST VALUE 47UF
J 0
(-1025 -725);
DISPLAY 0.617021 (-1025 -725);
PAINT SKYBLUE (-1025 -725);
FORCEPROP 1 LAST PART_NUMBER 602433-106
J 0
(-1025 -925);
DISPLAY 0.617021 (-1025 -925);
PAINT BLUE (-1025 -925);
FORCEPROP 0 LAST GROUP PWR_MLCC_CAP
J 0
(-1019 -1013);
DISPLAY 0.638298 (-1019 -1013);
PAINT BROWN (-1019 -1013);
DISPLAY BOTH (-1019 -1013);
FORCEPROP 1 LAST VOLTAGE 4V
J 0
(-1025 -775);
DISPLAY 0.617021 (-1025 -775);
PAINT SKYBLUE (-1025 -775);
FORCEPROP 1 LAST PACK_TYPE 0603V
J 0
(-1025 -975);
DISPLAY 0.617021 (-1025 -975);
PAINT SKYBLUE (-1025 -975);
FORCEPROP 1 LASTPIN (-1075 -675) $PN 1
J 0
(-1065 -695);
DISPLAY 0.617021 (-1065 -695);
PAINT ORANGE (-1065 -695);
FORCEPROP 1 LASTPIN (-1075 -875) $PN 2
J 0
(-1065 -895);
DISPLAY 0.617021 (-1065 -895);
PAINT ORANGE (-1065 -895);
FORCEPROP 1 LAST MATERIAL X5R
J 0
(-1025 -875);
DISPLAY 0.617021 (-1025 -875);
PAINT SKYBLUE (-1025 -875);
FORCEPROP 1 LAST TOLERANCE 20%
J 0
(-1025 -825);
DISPLAY 0.617021 (-1025 -825);
PAINT SKYBLUE (-1025 -825);
FORCEPROP 2 LAST CDS_SEC 1
J 0
(-1025 -625);
PAINT ORANGE (-1025 -625);
DISPLAY INVISIBLE (-1025 -625);
FORCEPROP 2 LAST SEC_TYPE 0603V
J 0
(-1025 -575);
DISPLAY 1.021277 (-1025 -575);
PAINT ORANGE (-1025 -575);
DISPLAY INVISIBLE (-1025 -575);
FORCEPROP 2 LAST SEC 1
J 0
(-1025 -575);
DISPLAY 0.680851 (-1025 -575);
PAINT MONO (-1025 -575);
DISPLAY INVISIBLE (-1025 -575);
FORCEPROP 2 LAST CDS_LIB dev_discrete
J 0
(-1075 -775);
PAINT ORANGE (-1075 -775);
DISPLAY INVISIBLE (-1075 -775);
FORCEPROP 1 LAST PATH I288
J 0
(-1025 -625);
DISPLAY 0.978723 (-1025 -625);
PAINT WHITE (-1025 -625);
DISPLAY INVISIBLE (-1025 -625);
FORCEPROP 2 LAST CDS_LOCATION C7L4
J 0
(-1025 -675);
DISPLAY 0.617021 (-1025 -675);
PAINT AQUA (-1025 -675);
DISPLAY INVISIBLE (-1025 -675);
FORCEADD CAP_A..1
(-775 -775);
FORCEPROP 0 LAST BOM_SS E15431-004
J 0
(-734 -1091);
DISPLAY 0.510638 (-734 -1091);
PAINT BROWN (-734 -1091);
DISPLAY BOTH (-734 -1091);
FORCEPROP 1 LAST LOCATION C8L8
J 0
(-725 -675);
DISPLAY 0.617021 (-725 -675);
PAINT AQUA (-725 -675);
FORCEPROP 1 LAST MATERIAL X5R
J 0
(-725 -875);
DISPLAY 0.617021 (-725 -875);
PAINT SKYBLUE (-725 -875);
FORCEPROP 1 LASTPIN (-775 -875) $PN 2
J 0
(-765 -895);
DISPLAY 0.617021 (-765 -895);
PAINT ORANGE (-765 -895);
FORCEPROP 1 LASTPIN (-775 -675) $PN 1
J 0
(-765 -695);
DISPLAY 0.617021 (-765 -695);
PAINT ORANGE (-765 -695);
FORCEPROP 1 LAST PACK_TYPE 0603V
J 0
(-725 -975);
DISPLAY 0.617021 (-725 -975);
PAINT SKYBLUE (-725 -975);
FORCEPROP 1 LAST VALUE 47UF
J 0
(-725 -725);
DISPLAY 0.617021 (-725 -725);
PAINT SKYBLUE (-725 -725);
FORCEPROP 1 LAST PART_NUMBER 602433-106
J 0
(-725 -925);
DISPLAY 0.617021 (-725 -925);
PAINT BLUE (-725 -925);
FORCEPROP 1 LAST VOLTAGE 4V
J 0
(-725 -775);
DISPLAY 0.617021 (-725 -775);
PAINT SKYBLUE (-725 -775);
FORCEPROP 1 LAST TOLERANCE 20%
J 0
(-725 -825);
DISPLAY 0.617021 (-725 -825);
PAINT SKYBLUE (-725 -825);
FORCEPROP 0 LAST GROUP PWR_MLCC_CAP
J 0
(-719 -1188);
DISPLAY 0.638298 (-719 -1188);
PAINT BROWN (-719 -1188);
DISPLAY BOTH (-719 -1188);
FORCEPROP 2 LAST CDS_LIB dev_discrete
J 0
(-775 -775);
PAINT ORANGE (-775 -775);
DISPLAY INVISIBLE (-775 -775);
FORCEPROP 2 LAST SEC 1
J 0
(-725 -575);
DISPLAY 0.680851 (-725 -575);
PAINT MONO (-725 -575);
DISPLAY INVISIBLE (-725 -575);
FORCEPROP 2 LAST SEC_TYPE 0603V
J 0
(-725 -575);
DISPLAY 1.021277 (-725 -575);
PAINT ORANGE (-725 -575);
DISPLAY INVISIBLE (-725 -575);
FORCEPROP 2 LAST CDS_SEC 1
J 0
(-725 -625);
PAINT ORANGE (-725 -625);
DISPLAY INVISIBLE (-725 -625);
FORCEPROP 1 LAST PATH I289
J 0
(-725 -625);
DISPLAY 0.978723 (-725 -625);
PAINT WHITE (-725 -625);
DISPLAY INVISIBLE (-725 -625);
FORCEPROP 2 LAST CDS_LOCATION C8L8
J 0
(-725 -675);
DISPLAY 0.617021 (-725 -675);
PAINT AQUA (-725 -675);
DISPLAY INVISIBLE (-725 -675);
FORCEADD CAP_A..1
(-475 -775);
FORCEPROP 0 LAST BOM_SS E15431-004
J 0
(-445 -1063);
DISPLAY 0.510638 (-445 -1063);
PAINT BROWN (-445 -1063);
DISPLAY BOTH (-445 -1063);
FORCEPROP 1 LAST VOLTAGE 4V
J 0
(-425 -775);
DISPLAY 0.617021 (-425 -775);
PAINT SKYBLUE (-425 -775);
FORCEPROP 1 LAST TOLERANCE 20%
J 0
(-425 -825);
DISPLAY 0.617021 (-425 -825);
PAINT SKYBLUE (-425 -825);
FORCEPROP 0 LAST GROUP PWR_MLCC_CAP
J 0
(-419 -1013);
DISPLAY 0.638298 (-419 -1013);
PAINT BROWN (-419 -1013);
DISPLAY BOTH (-419 -1013);
FORCEPROP 1 LAST PACK_TYPE 0603V
J 0
(-425 -975);
DISPLAY 0.617021 (-425 -975);
PAINT SKYBLUE (-425 -975);
FORCEPROP 1 LAST PART_NUMBER 602433-106
J 0
(-425 -925);
DISPLAY 0.617021 (-425 -925);
PAINT BLUE (-425 -925);
FORCEPROP 1 LAST VALUE 47UF
J 0
(-425 -725);
DISPLAY 0.617021 (-425 -725);
PAINT SKYBLUE (-425 -725);
FORCEPROP 1 LASTPIN (-475 -675) $PN 1
J 0
(-465 -695);
DISPLAY 0.617021 (-465 -695);
PAINT ORANGE (-465 -695);
FORCEPROP 1 LASTPIN (-475 -875) $PN 2
J 0
(-465 -895);
DISPLAY 0.617021 (-465 -895);
PAINT ORANGE (-465 -895);
FORCEPROP 1 LAST MATERIAL X5R
J 0
(-425 -875);
DISPLAY 0.617021 (-425 -875);
PAINT SKYBLUE (-425 -875);
FORCEPROP 1 LAST LOCATION C8L9
J 0
(-425 -675);
DISPLAY 0.617021 (-425 -675);
PAINT AQUA (-425 -675);
FORCEPROP 2 LAST CDS_SEC 1
J 0
(-425 -625);
PAINT ORANGE (-425 -625);
DISPLAY INVISIBLE (-425 -625);
FORCEPROP 2 LAST SEC_TYPE 0603V
J 0
(-425 -575);
DISPLAY 1.021277 (-425 -575);
PAINT ORANGE (-425 -575);
DISPLAY INVISIBLE (-425 -575);
FORCEPROP 2 LAST SEC 1
J 0
(-425 -575);
DISPLAY 0.680851 (-425 -575);
PAINT MONO (-425 -575);
DISPLAY INVISIBLE (-425 -575);
FORCEPROP 2 LAST CDS_LIB dev_discrete
J 0
(-475 -775);
PAINT ORANGE (-475 -775);
DISPLAY INVISIBLE (-475 -775);
FORCEPROP 1 LAST PATH I290
J 0
(-425 -625);
DISPLAY 0.978723 (-425 -625);
PAINT WHITE (-425 -625);
DISPLAY INVISIBLE (-425 -625);
FORCEPROP 2 LAST CDS_LOCATION C8L9
J 0
(-425 -675);
DISPLAY 0.617021 (-425 -675);
PAINT AQUA (-425 -675);
DISPLAY INVISIBLE (-425 -675);
FORCEADD CAP_A..1
(-200 -775);
FORCEPROP 0 LAST BOM_SS E15431-004
J 0
(-190 -1099);
DISPLAY 0.510638 (-190 -1099);
PAINT BROWN (-190 -1099);
DISPLAY BOTH (-190 -1099);
FORCEPROP 1 LAST VOLTAGE 4V
J 0
(-150 -775);
DISPLAY 0.617021 (-150 -775);
PAINT SKYBLUE (-150 -775);
FORCEPROP 1 LAST TOLERANCE 20%
J 0
(-150 -825);
DISPLAY 0.617021 (-150 -825);
PAINT SKYBLUE (-150 -825);
FORCEPROP 1 LASTPIN (-200 -875) $PN 2
J 0
(-190 -895);
DISPLAY 0.617021 (-190 -895);
PAINT ORANGE (-190 -895);
FORCEPROP 1 LAST MATERIAL X5R
J 0
(-150 -875);
DISPLAY 0.617021 (-150 -875);
PAINT SKYBLUE (-150 -875);
FORCEPROP 1 LAST PART_NUMBER 602433-106
J 0
(-150 -925);
DISPLAY 0.617021 (-150 -925);
PAINT BLUE (-150 -925);
FORCEPROP 1 LAST PACK_TYPE 0603V
J 0
(-150 -975);
DISPLAY 0.617021 (-150 -975);
PAINT SKYBLUE (-150 -975);
FORCEPROP 0 LAST GROUP PWR_MLCC_CAP
J 0
(-144 -1163);
DISPLAY 0.638298 (-144 -1163);
PAINT BROWN (-144 -1163);
DISPLAY BOTH (-144 -1163);
FORCEPROP 1 LASTPIN (-200 -675) $PN 1
J 0
(-190 -695);
DISPLAY 0.617021 (-190 -695);
PAINT ORANGE (-190 -695);
FORCEPROP 1 LAST LOCATION C8M6
J 0
(-150 -675);
DISPLAY 0.617021 (-150 -675);
PAINT AQUA (-150 -675);
FORCEPROP 1 LAST VALUE 47UF
J 0
(-150 -725);
DISPLAY 0.617021 (-150 -725);
PAINT SKYBLUE (-150 -725);
FORCEPROP 2 LAST CDS_LIB dev_discrete
J 0
(-200 -775);
PAINT ORANGE (-200 -775);
DISPLAY INVISIBLE (-200 -775);
FORCEPROP 2 LAST SEC 1
J 0
(-150 -575);
DISPLAY 0.680851 (-150 -575);
PAINT MONO (-150 -575);
DISPLAY INVISIBLE (-150 -575);
FORCEPROP 2 LAST SEC_TYPE 0603V
J 0
(-150 -575);
DISPLAY 1.021277 (-150 -575);
PAINT ORANGE (-150 -575);
DISPLAY INVISIBLE (-150 -575);
FORCEPROP 2 LAST CDS_SEC 1
J 0
(-150 -625);
PAINT ORANGE (-150 -625);
DISPLAY INVISIBLE (-150 -625);
FORCEPROP 1 LAST PATH I291
J 0
(-150 -625);
DISPLAY 0.978723 (-150 -625);
PAINT WHITE (-150 -625);
DISPLAY INVISIBLE (-150 -625);
FORCEPROP 2 LAST CDS_LOCATION C8M6
J 0
(-150 -675);
DISPLAY 0.617021 (-150 -675);
PAINT AQUA (-150 -675);
DISPLAY INVISIBLE (-150 -675);
FORCEADD CAP_A..1
(125 -775);
FORCEPROP 0 LAST BOM_SS E15431-004
J 0
(133 -1060);
DISPLAY 0.510638 (133 -1060);
PAINT BROWN (133 -1060);
DISPLAY BOTH (133 -1060);
FORCEPROP 1 LAST TOLERANCE 20%
J 0
(175 -825);
DISPLAY 0.617021 (175 -825);
PAINT SKYBLUE (175 -825);
FORCEPROP 1 LAST VALUE 47UF
J 0
(175 -725);
DISPLAY 0.617021 (175 -725);
PAINT SKYBLUE (175 -725);
FORCEPROP 1 LAST PACK_TYPE 0603V
J 0
(175 -975);
DISPLAY 0.617021 (175 -975);
PAINT SKYBLUE (175 -975);
FORCEPROP 1 LASTPIN (125 -675) $PN 1
J 0
(135 -695);
DISPLAY 0.617021 (135 -695);
PAINT ORANGE (135 -695);
FORCEPROP 1 LASTPIN (125 -875) $PN 2
J 0
(135 -895);
DISPLAY 0.617021 (135 -895);
PAINT ORANGE (135 -895);
FORCEPROP 1 LAST MATERIAL X5R
J 0
(175 -875);
DISPLAY 0.617021 (175 -875);
PAINT SKYBLUE (175 -875);
FORCEPROP 1 LAST PART_NUMBER 602433-106
J 0
(175 -925);
DISPLAY 0.617021 (175 -925);
PAINT BLUE (175 -925);
FORCEPROP 1 LAST VOLTAGE 4V
J 0
(175 -775);
DISPLAY 0.617021 (175 -775);
PAINT SKYBLUE (175 -775);
FORCEPROP 1 LAST LOCATION C2A4
J 0
(175 -675);
DISPLAY 0.617021 (175 -675);
PAINT AQUA (175 -675);
FORCEPROP 0 LAST GROUP PWR_MLCC_CAP
J 0
(181 -1013);
DISPLAY 0.638298 (181 -1013);
PAINT BROWN (181 -1013);
DISPLAY BOTH (181 -1013);
FORCEPROP 2 LAST CDS_SEC 1
J 0
(175 -625);
PAINT ORANGE (175 -625);
DISPLAY INVISIBLE (175 -625);
FORCEPROP 2 LAST SEC_TYPE 0603V
J 0
(175 -575);
DISPLAY 1.021277 (175 -575);
PAINT ORANGE (175 -575);
DISPLAY INVISIBLE (175 -575);
FORCEPROP 2 LAST SEC 1
J 0
(175 -575);
DISPLAY 0.680851 (175 -575);
PAINT MONO (175 -575);
DISPLAY INVISIBLE (175 -575);
FORCEPROP 2 LAST CDS_LIB dev_discrete
J 0
(125 -775);
PAINT ORANGE (125 -775);
DISPLAY INVISIBLE (125 -775);
FORCEPROP 1 LAST PATH I292
J 0
(175 -625);
DISPLAY 0.978723 (175 -625);
PAINT WHITE (175 -625);
DISPLAY INVISIBLE (175 -625);
FORCEPROP 2 LAST CDS_LOCATION C2A4
J 0
(175 -675);
DISPLAY 0.617021 (175 -675);
PAINT AQUA (175 -675);
DISPLAY INVISIBLE (175 -675);
FORCEADD CAP_A..1
(425 -775);
FORCEPROP 0 LAST BOM_SS E15431-004
J 0
(468 -1084);
DISPLAY 0.510638 (468 -1084);
PAINT BROWN (468 -1084);
DISPLAY BOTH (468 -1084);
FORCEPROP 1 LAST TOLERANCE 20%
J 0
(475 -825);
DISPLAY 0.617021 (475 -825);
PAINT SKYBLUE (475 -825);
FORCEPROP 1 LASTPIN (425 -875) $PN 2
J 0
(435 -895);
DISPLAY 0.617021 (435 -895);
PAINT ORANGE (435 -895);
FORCEPROP 1 LASTPIN (425 -675) $PN 1
J 0
(435 -695);
DISPLAY 0.617021 (435 -695);
PAINT ORANGE (435 -695);
FORCEPROP 1 LAST PACK_TYPE 0603V
J 0
(475 -975);
DISPLAY 0.617021 (475 -975);
PAINT SKYBLUE (475 -975);
FORCEPROP 1 LAST VOLTAGE 4V
J 0
(475 -775);
DISPLAY 0.617021 (475 -775);
PAINT SKYBLUE (475 -775);
FORCEPROP 1 LAST PART_NUMBER 602433-106
J 0
(475 -925);
DISPLAY 0.617021 (475 -925);
PAINT BLUE (475 -925);
FORCEPROP 1 LAST MATERIAL X5R
J 0
(475 -875);
DISPLAY 0.617021 (475 -875);
PAINT SKYBLUE (475 -875);
FORCEPROP 1 LAST VALUE 47UF
J 0
(475 -725);
DISPLAY 0.617021 (475 -725);
PAINT SKYBLUE (475 -725);
FORCEPROP 1 LAST LOCATION C8M4
J 0
(475 -675);
DISPLAY 0.617021 (475 -675);
PAINT AQUA (475 -675);
FORCEPROP 0 LAST GROUP PWR_MLCC_CAP
J 0
(481 -1163);
DISPLAY 0.638298 (481 -1163);
PAINT BROWN (481 -1163);
DISPLAY BOTH (481 -1163);
FORCEPROP 2 LAST CDS_LIB dev_discrete
J 0
(425 -775);
PAINT ORANGE (425 -775);
DISPLAY INVISIBLE (425 -775);
FORCEPROP 2 LAST SEC 1
J 0
(475 -575);
DISPLAY 0.680851 (475 -575);
PAINT MONO (475 -575);
DISPLAY INVISIBLE (475 -575);
FORCEPROP 2 LAST SEC_TYPE 0603V
J 0
(475 -575);
DISPLAY 1.021277 (475 -575);
PAINT ORANGE (475 -575);
DISPLAY INVISIBLE (475 -575);
FORCEPROP 2 LAST CDS_SEC 1
J 0
(475 -625);
PAINT ORANGE (475 -625);
DISPLAY INVISIBLE (475 -625);
FORCEPROP 1 LAST PATH I293
J 0
(475 -625);
DISPLAY 0.978723 (475 -625);
PAINT WHITE (475 -625);
DISPLAY INVISIBLE (475 -625);
FORCEPROP 2 LAST CDS_LOCATION C8M4
J 0
(475 -675);
DISPLAY 0.617021 (475 -675);
PAINT AQUA (475 -675);
DISPLAY INVISIBLE (475 -675);
FORCEADD CAP_A..1
(725 -775);
FORCEPROP 0 LAST BOM_SS E15431-004
J 0
(744 -1049);
DISPLAY 0.510638 (744 -1049);
PAINT BROWN (744 -1049);
DISPLAY BOTH (744 -1049);
FORCEPROP 1 LAST MATERIAL X5R
J 0
(775 -875);
DISPLAY 0.617021 (775 -875);
PAINT SKYBLUE (775 -875);
FORCEPROP 1 LAST PACK_TYPE 0603V
J 0
(775 -975);
DISPLAY 0.617021 (775 -975);
PAINT SKYBLUE (775 -975);
FORCEPROP 1 LASTPIN (725 -675) $PN 1
J 0
(735 -695);
DISPLAY 0.617021 (735 -695);
PAINT ORANGE (735 -695);
FORCEPROP 1 LAST TOLERANCE 20%
J 0
(775 -825);
DISPLAY 0.617021 (775 -825);
PAINT SKYBLUE (775 -825);
FORCEPROP 1 LAST VOLTAGE 4V
J 0
(775 -775);
DISPLAY 0.617021 (775 -775);
PAINT SKYBLUE (775 -775);
FORCEPROP 1 LAST VALUE 47UF
J 0
(775 -725);
DISPLAY 0.617021 (775 -725);
PAINT SKYBLUE (775 -725);
FORCEPROP 1 LAST LOCATION C7M2
J 0
(775 -675);
DISPLAY 0.617021 (775 -675);
PAINT AQUA (775 -675);
FORCEPROP 1 LAST PART_NUMBER 602433-106
J 0
(775 -925);
DISPLAY 0.617021 (775 -925);
PAINT BLUE (775 -925);
FORCEPROP 1 LASTPIN (725 -875) $PN 2
J 0
(735 -895);
DISPLAY 0.617021 (735 -895);
PAINT ORANGE (735 -895);
FORCEPROP 0 LAST GROUP PWR_MLCC_CAP
J 0
(781 -1013);
DISPLAY 0.638298 (781 -1013);
PAINT BROWN (781 -1013);
DISPLAY BOTH (781 -1013);
FORCEPROP 2 LAST CDS_SEC 1
J 0
(775 -625);
PAINT ORANGE (775 -625);
DISPLAY INVISIBLE (775 -625);
FORCEPROP 2 LAST SEC_TYPE 0603V
J 0
(775 -575);
DISPLAY 1.021277 (775 -575);
PAINT ORANGE (775 -575);
DISPLAY INVISIBLE (775 -575);
FORCEPROP 2 LAST SEC 1
J 0
(775 -575);
DISPLAY 0.680851 (775 -575);
PAINT MONO (775 -575);
DISPLAY INVISIBLE (775 -575);
FORCEPROP 2 LAST CDS_LIB dev_discrete
J 0
(725 -775);
PAINT ORANGE (725 -775);
DISPLAY INVISIBLE (725 -775);
FORCEPROP 1 LAST PATH I294
J 0
(775 -625);
DISPLAY 0.978723 (775 -625);
PAINT WHITE (775 -625);
DISPLAY INVISIBLE (775 -625);
FORCEPROP 2 LAST CDS_LOCATION C7M2
J 0
(775 -675);
DISPLAY 0.617021 (775 -675);
PAINT AQUA (775 -675);
DISPLAY INVISIBLE (775 -675);
FORCEADD CAP_A..1
(1000 -775);
FORCEPROP 0 LAST BOM_SS E15431-004
J 0
(1012 -1110);
DISPLAY 0.510638 (1012 -1110);
PAINT BROWN (1012 -1110);
DISPLAY BOTH (1012 -1110);
FORCEPROP 1 LAST MATERIAL X5R
J 0
(1050 -875);
DISPLAY 0.617021 (1050 -875);
PAINT SKYBLUE (1050 -875);
FORCEPROP 1 LAST PACK_TYPE 0603V
J 0
(1050 -975);
DISPLAY 0.617021 (1050 -975);
PAINT SKYBLUE (1050 -975);
FORCEPROP 1 LAST TOLERANCE 20%
J 0
(1050 -825);
DISPLAY 0.617021 (1050 -825);
PAINT SKYBLUE (1050 -825);
FORCEPROP 1 LASTPIN (1000 -875) $PN 2
J 0
(1010 -895);
DISPLAY 0.617021 (1010 -895);
PAINT ORANGE (1010 -895);
FORCEPROP 1 LASTPIN (1000 -675) $PN 1
J 0
(1010 -695);
DISPLAY 0.617021 (1010 -695);
PAINT ORANGE (1010 -695);
FORCEPROP 1 LAST VALUE 47UF
J 0
(1050 -725);
DISPLAY 0.617021 (1050 -725);
PAINT SKYBLUE (1050 -725);
FORCEPROP 1 LAST VOLTAGE 4V
J 0
(1050 -775);
DISPLAY 0.617021 (1050 -775);
PAINT SKYBLUE (1050 -775);
FORCEPROP 1 LAST PART_NUMBER 602433-106
J 0
(1050 -925);
DISPLAY 0.617021 (1050 -925);
PAINT BLUE (1050 -925);
FORCEPROP 1 LAST LOCATION C7M1
J 0
(1050 -675);
DISPLAY 0.617021 (1050 -675);
PAINT AQUA (1050 -675);
FORCEPROP 0 LAST GROUP PWR_MLCC_CAP
J 0
(1056 -1163);
DISPLAY 0.638298 (1056 -1163);
PAINT BROWN (1056 -1163);
DISPLAY BOTH (1056 -1163);
FORCEPROP 2 LAST CDS_LIB dev_discrete
J 0
(1000 -775);
PAINT ORANGE (1000 -775);
DISPLAY INVISIBLE (1000 -775);
FORCEPROP 2 LAST SEC 1
J 0
(1050 -575);
DISPLAY 0.680851 (1050 -575);
PAINT MONO (1050 -575);
DISPLAY INVISIBLE (1050 -575);
FORCEPROP 2 LAST SEC_TYPE 0603V
J 0
(1050 -575);
DISPLAY 1.021277 (1050 -575);
PAINT ORANGE (1050 -575);
DISPLAY INVISIBLE (1050 -575);
FORCEPROP 2 LAST CDS_SEC 1
J 0
(1050 -625);
PAINT ORANGE (1050 -625);
DISPLAY INVISIBLE (1050 -625);
FORCEPROP 1 LAST PATH I295
J 0
(1050 -625);
DISPLAY 0.978723 (1050 -625);
PAINT WHITE (1050 -625);
DISPLAY INVISIBLE (1050 -625);
FORCEPROP 2 LAST CDS_LOCATION C7M1
J 0
(1050 -675);
DISPLAY 0.617021 (1050 -675);
PAINT AQUA (1050 -675);
DISPLAY INVISIBLE (1050 -675);
FORCEADD CAP_A..1
(1275 -775);
FORCEPROP 0 LAST BOM_SS E15431-004
J 0
(1288 -1053);
DISPLAY 0.510638 (1288 -1053);
PAINT BROWN (1288 -1053);
DISPLAY BOTH (1288 -1053);
FORCEPROP 1 LAST MATERIAL X5R
J 0
(1325 -875);
DISPLAY 0.617021 (1325 -875);
PAINT SKYBLUE (1325 -875);
FORCEPROP 1 LAST VOLTAGE 4V
J 0
(1325 -775);
DISPLAY 0.617021 (1325 -775);
PAINT SKYBLUE (1325 -775);
FORCEPROP 1 LAST PART_NUMBER 602433-106
J 0
(1325 -925);
DISPLAY 0.617021 (1325 -925);
PAINT BLUE (1325 -925);
FORCEPROP 1 LAST VALUE 47UF
J 0
(1325 -725);
DISPLAY 0.617021 (1325 -725);
PAINT SKYBLUE (1325 -725);
FORCEPROP 1 LASTPIN (1275 -675) $PN 1
J 0
(1285 -695);
DISPLAY 0.617021 (1285 -695);
PAINT ORANGE (1285 -695);
FORCEPROP 1 LAST LOCATION C2A3
J 0
(1325 -675);
DISPLAY 0.617021 (1325 -675);
PAINT AQUA (1325 -675);
FORCEPROP 1 LAST PACK_TYPE 0603V
J 0
(1325 -975);
DISPLAY 0.617021 (1325 -975);
PAINT SKYBLUE (1325 -975);
FORCEPROP 1 LAST TOLERANCE 20%
J 0
(1325 -825);
DISPLAY 0.617021 (1325 -825);
PAINT SKYBLUE (1325 -825);
FORCEPROP 1 LASTPIN (1275 -875) $PN 2
J 0
(1285 -895);
DISPLAY 0.617021 (1285 -895);
PAINT ORANGE (1285 -895);
FORCEPROP 0 LAST GROUP PWR_MLCC_CAP
J 0
(1331 -1013);
DISPLAY 0.638298 (1331 -1013);
PAINT BROWN (1331 -1013);
DISPLAY BOTH (1331 -1013);
FORCEPROP 2 LAST CDS_SEC 1
J 0
(1325 -625);
PAINT ORANGE (1325 -625);
DISPLAY INVISIBLE (1325 -625);
FORCEPROP 2 LAST SEC_TYPE 0603V
J 0
(1325 -575);
DISPLAY 1.021277 (1325 -575);
PAINT ORANGE (1325 -575);
DISPLAY INVISIBLE (1325 -575);
FORCEPROP 2 LAST SEC 1
J 0
(1325 -575);
DISPLAY 0.680851 (1325 -575);
PAINT MONO (1325 -575);
DISPLAY INVISIBLE (1325 -575);
FORCEPROP 2 LAST CDS_LIB dev_discrete
J 0
(1275 -775);
PAINT ORANGE (1275 -775);
DISPLAY INVISIBLE (1275 -775);
FORCEPROP 1 LAST PATH I296
J 0
(1325 -625);
DISPLAY 0.978723 (1325 -625);
PAINT WHITE (1325 -625);
DISPLAY INVISIBLE (1325 -625);
FORCEPROP 2 LAST CDS_LOCATION C2A3
J 0
(1325 -675);
DISPLAY 0.617021 (1325 -675);
PAINT AQUA (1325 -675);
DISPLAY INVISIBLE (1325 -675);
FORCEADD CAP_A..1
(1575 -775);
FORCEPROP 0 LAST BOM_SS E15431-004
J 0
(1596 -1101);
DISPLAY 0.510638 (1596 -1101);
PAINT BROWN (1596 -1101);
DISPLAY BOTH (1596 -1101);
FORCEPROP 1 LAST MATERIAL X5R
J 0
(1625 -875);
DISPLAY 0.617021 (1625 -875);
PAINT SKYBLUE (1625 -875);
FORCEPROP 1 LAST TOLERANCE 20%
J 0
(1625 -825);
DISPLAY 0.617021 (1625 -825);
PAINT SKYBLUE (1625 -825);
FORCEPROP 1 LASTPIN (1575 -875) $PN 2
J 0
(1585 -895);
DISPLAY 0.617021 (1585 -895);
PAINT ORANGE (1585 -895);
FORCEPROP 1 LASTPIN (1575 -675) $PN 1
J 0
(1585 -695);
DISPLAY 0.617021 (1585 -695);
PAINT ORANGE (1585 -695);
FORCEPROP 1 LAST PACK_TYPE 0603V
J 0
(1625 -975);
DISPLAY 0.617021 (1625 -975);
PAINT SKYBLUE (1625 -975);
FORCEPROP 1 LAST VALUE 47UF
J 0
(1625 -725);
DISPLAY 0.617021 (1625 -725);
PAINT SKYBLUE (1625 -725);
FORCEPROP 1 LAST PART_NUMBER 602433-106
J 0
(1625 -925);
DISPLAY 0.617021 (1625 -925);
PAINT BLUE (1625 -925);
FORCEPROP 1 LAST LOCATION C8L10
J 0
(1625 -675);
DISPLAY 0.617021 (1625 -675);
PAINT AQUA (1625 -675);
FORCEPROP 1 LAST VOLTAGE 4V
J 0
(1625 -775);
DISPLAY 0.617021 (1625 -775);
PAINT SKYBLUE (1625 -775);
FORCEPROP 0 LAST GROUP PWR_MLCC_CAP
J 0
(1631 -1163);
DISPLAY 0.638298 (1631 -1163);
PAINT BROWN (1631 -1163);
DISPLAY BOTH (1631 -1163);
FORCEPROP 2 LAST CDS_LIB dev_discrete
J 0
(1575 -775);
PAINT ORANGE (1575 -775);
DISPLAY INVISIBLE (1575 -775);
FORCEPROP 2 LAST SEC 1
J 0
(1625 -575);
DISPLAY 0.680851 (1625 -575);
PAINT MONO (1625 -575);
DISPLAY INVISIBLE (1625 -575);
FORCEPROP 2 LAST SEC_TYPE 0603V
J 0
(1625 -575);
DISPLAY 1.021277 (1625 -575);
PAINT ORANGE (1625 -575);
DISPLAY INVISIBLE (1625 -575);
FORCEPROP 2 LAST CDS_SEC 1
J 0
(1625 -625);
PAINT ORANGE (1625 -625);
DISPLAY INVISIBLE (1625 -625);
FORCEPROP 1 LAST PATH I297
J 0
(1625 -625);
DISPLAY 0.978723 (1625 -625);
PAINT WHITE (1625 -625);
DISPLAY INVISIBLE (1625 -625);
FORCEPROP 2 LAST CDS_LOCATION C8L10
J 0
(1625 -675);
DISPLAY 0.617021 (1625 -675);
PAINT AQUA (1625 -675);
DISPLAY INVISIBLE (1625 -675);
FORCEADD CAP_A..1
(1875 -775);
FORCEPROP 0 LAST BOM_SS E15431-004
J 0
(1867 -1043);
DISPLAY 0.510638 (1867 -1043);
PAINT BROWN (1867 -1043);
DISPLAY BOTH (1867 -1043);
FORCEPROP 1 LAST MATERIAL X5R
J 0
(1925 -875);
DISPLAY 0.617021 (1925 -875);
PAINT SKYBLUE (1925 -875);
FORCEPROP 1 LAST VOLTAGE 4V
J 0
(1925 -775);
DISPLAY 0.617021 (1925 -775);
PAINT SKYBLUE (1925 -775);
FORCEPROP 1 LAST PART_NUMBER 602433-106
J 0
(1925 -925);
DISPLAY 0.617021 (1925 -925);
PAINT BLUE (1925 -925);
FORCEPROP 1 LAST VALUE 47UF
J 0
(1925 -725);
DISPLAY 0.617021 (1925 -725);
PAINT SKYBLUE (1925 -725);
FORCEPROP 1 LAST PACK_TYPE 0603V
J 0
(1925 -975);
DISPLAY 0.617021 (1925 -975);
PAINT SKYBLUE (1925 -975);
FORCEPROP 1 LASTPIN (1875 -875) $PN 2
J 0
(1885 -895);
DISPLAY 0.617021 (1885 -895);
PAINT ORANGE (1885 -895);
FORCEPROP 1 LAST TOLERANCE 20%
J 0
(1925 -825);
DISPLAY 0.617021 (1925 -825);
PAINT SKYBLUE (1925 -825);
FORCEPROP 1 LAST LOCATION C8M5
J 0
(1925 -675);
DISPLAY 0.617021 (1925 -675);
PAINT AQUA (1925 -675);
FORCEPROP 1 LASTPIN (1875 -675) $PN 1
J 0
(1885 -695);
DISPLAY 0.617021 (1885 -695);
PAINT ORANGE (1885 -695);
FORCEPROP 0 LAST GROUP PWR_MLCC_CAP
J 0
(1931 -1013);
DISPLAY 0.638298 (1931 -1013);
PAINT BROWN (1931 -1013);
DISPLAY BOTH (1931 -1013);
FORCEPROP 2 LAST CDS_SEC 1
J 0
(1925 -625);
PAINT ORANGE (1925 -625);
DISPLAY INVISIBLE (1925 -625);
FORCEPROP 2 LAST SEC_TYPE 0603V
J 0
(1925 -575);
DISPLAY 1.021277 (1925 -575);
PAINT ORANGE (1925 -575);
DISPLAY INVISIBLE (1925 -575);
FORCEPROP 2 LAST SEC 1
J 0
(1925 -575);
DISPLAY 0.680851 (1925 -575);
PAINT MONO (1925 -575);
DISPLAY INVISIBLE (1925 -575);
FORCEPROP 2 LAST CDS_LIB dev_discrete
J 0
(1875 -775);
PAINT ORANGE (1875 -775);
DISPLAY INVISIBLE (1875 -775);
FORCEPROP 1 LAST PATH I298
J 0
(1925 -625);
DISPLAY 0.978723 (1925 -625);
PAINT WHITE (1925 -625);
DISPLAY INVISIBLE (1925 -625);
FORCEPROP 2 LAST CDS_LOCATION C8M5
J 0
(1925 -675);
DISPLAY 0.617021 (1925 -675);
PAINT AQUA (1925 -675);
DISPLAY INVISIBLE (1925 -675);
FORCEADD CAP_A..1
(2150 -775);
FORCEPROP 1 LAST MATERIAL X5R
J 0
(2200 -875);
DISPLAY 0.617021 (2200 -875);
PAINT SKYBLUE (2200 -875);
FORCEPROP 0 LAST BOM_SS E15431-004
J 0
(2160 -1091);
DISPLAY 0.510638 (2160 -1091);
PAINT BROWN (2160 -1091);
DISPLAY BOTH (2160 -1091);
FORCEPROP 1 LAST VOLTAGE 4V
J 0
(2200 -775);
DISPLAY 0.617021 (2200 -775);
PAINT SKYBLUE (2200 -775);
FORCEPROP 1 LASTPIN (2150 -675) $PN 1
J 0
(2160 -695);
DISPLAY 0.617021 (2160 -695);
PAINT ORANGE (2160 -695);
FORCEPROP 1 LASTPIN (2150 -875) $PN 2
J 0
(2160 -895);
DISPLAY 0.617021 (2160 -895);
PAINT ORANGE (2160 -895);
FORCEPROP 1 LAST LOCATION C8M3
J 0
(2200 -675);
DISPLAY 0.617021 (2200 -675);
PAINT AQUA (2200 -675);
FORCEPROP 1 LAST VALUE 47UF
J 0
(2200 -725);
DISPLAY 0.617021 (2200 -725);
PAINT SKYBLUE (2200 -725);
FORCEPROP 1 LAST PACK_TYPE 0603V
J 0
(2200 -975);
DISPLAY 0.617021 (2200 -975);
PAINT SKYBLUE (2200 -975);
FORCEPROP 1 LAST PART_NUMBER 602433-106
J 0
(2200 -925);
DISPLAY 0.617021 (2200 -925);
PAINT BLUE (2200 -925);
FORCEPROP 1 LAST TOLERANCE 20%
J 0
(2200 -825);
DISPLAY 0.617021 (2200 -825);
PAINT SKYBLUE (2200 -825);
FORCEPROP 0 LAST GROUP PWR_MLCC_CAP
J 0
(2206 -1163);
DISPLAY 0.638298 (2206 -1163);
PAINT BROWN (2206 -1163);
DISPLAY BOTH (2206 -1163);
FORCEPROP 1 LAST PATH I299
J 0
(2200 -625);
DISPLAY 0.978723 (2200 -625);
PAINT WHITE (2200 -625);
DISPLAY INVISIBLE (2200 -625);
FORCEPROP 2 LAST CDS_SEC 1
J 0
(2200 -625);
PAINT ORANGE (2200 -625);
DISPLAY INVISIBLE (2200 -625);
FORCEPROP 2 LAST SEC_TYPE 0603V
J 0
(2200 -575);
DISPLAY 1.021277 (2200 -575);
PAINT ORANGE (2200 -575);
DISPLAY INVISIBLE (2200 -575);
FORCEPROP 2 LAST SEC 1
J 0
(2200 -575);
DISPLAY 0.680851 (2200 -575);
PAINT MONO (2200 -575);
DISPLAY INVISIBLE (2200 -575);
FORCEPROP 2 LAST CDS_LIB dev_discrete
J 0
(2150 -775);
PAINT ORANGE (2150 -775);
DISPLAY INVISIBLE (2150 -775);
FORCEPROP 2 LAST CDS_LOCATION C8M3
J 0
(2200 -675);
DISPLAY 0.617021 (2200 -675);
PAINT AQUA (2200 -675);
DISPLAY INVISIBLE (2200 -675);
FORCEADD CAP..1
(2400 2825);
FORCEPROP 1 LAST LOCATION C8L1
J 0
(2450 2925);
DISPLAY 0.617021 (2450 2925);
PAINT AQUA (2450 2925);
FORCEPROP 1 LASTPIN (2400 2725) $PN 2
J 0
(2410 2705);
DISPLAY 0.617021 (2410 2705);
PAINT ORANGE (2410 2705);
FORCEPROP 1 LASTPIN (2400 2925) $PN 1
J 0
(2410 2905);
DISPLAY 0.617021 (2410 2905);
PAINT ORANGE (2410 2905);
FORCEPROP 1 LAST VALUE 100UF
J 0
(2450 2875);
DISPLAY 0.617021 (2450 2875);
PAINT SKYBLUE (2450 2875);
FORCEPROP 1 LAST VOLTAGE 4V
J 0
(2450 2825);
DISPLAY 0.617021 (2450 2825);
PAINT SKYBLUE (2450 2825);
FORCEPROP 1 LAST TOLERANCE 20%
J 0
(2450 2775);
DISPLAY 0.617021 (2450 2775);
PAINT SKYBLUE (2450 2775);
FORCEPROP 1 LAST PART_NUMBER 602433-112
J 0
(2450 2725);
DISPLAY 0.617021 (2450 2725);
PAINT BLUE (2450 2725);
FORCEPROP 1 LAST PACK_TYPE 0805
J 0
(2450 2675);
DISPLAY 0.617021 (2450 2675);
PAINT SKYBLUE (2450 2675);
FORCEPROP 0 LAST NEW_MATERIAL X6S
J 0
(2450 2575);
DISPLAY 0.638298 (2450 2575);
PAINT BROWN (2450 2575);
DISPLAY BOTH (2450 2575);
FORCEPROP 0 LAST BOM_SS NOPOP
J 0
(2438 2518);
DISPLAY 0.638298 (2438 2518);
PAINT BROWN (2438 2518);
DISPLAY BOTH (2438 2518);
FORCEPROP 0 LAST GROUP PWR_MLCC_CAP
J 0
(2456 2462);
DISPLAY 0.638298 (2456 2462);
PAINT BROWN (2456 2462);
DISPLAY BOTH (2456 2462);
FORCEPROP 0 LAST NEW_PN 078.1071T.M002
J 0
(2443 2630);
DISPLAY 0.638298 (2443 2630);
PAINT BROWN (2443 2630);
DISPLAY BOTH (2443 2630);
FORCEPROP 2 LAST CDS_LOCATION C8L1
J 0
(2450 2925);
DISPLAY 0.617021 (2450 2925);
PAINT AQUA (2450 2925);
DISPLAY INVISIBLE (2450 2925);
FORCEPROP 1 LAST MATERIAL X5R
J 0
(2450 2725);
DISPLAY 0.617021 (2450 2725);
PAINT SKYBLUE (2450 2725);
DISPLAY INVISIBLE (2450 2725);
FORCEPROP 2 LAST SEC 1
J 0
(2450 3025);
DISPLAY 0.680851 (2450 3025);
PAINT MONO (2450 3025);
DISPLAY INVISIBLE (2450 3025);
FORCEPROP 2 LAST SEC_TYPE 0805
J 0
(2450 3025);
DISPLAY 1.021277 (2450 3025);
PAINT ORANGE (2450 3025);
DISPLAY INVISIBLE (2450 3025);
FORCEPROP 2 LAST ROOM VDDQ_ABC_PWR_VR
J 0
(2450 2975);
PAINT MONO (2450 2975);
DISPLAY INVISIBLE (2450 2975);
FORCEPROP 2 LAST BOM_COST MEM_VRD_PVDDQ_CD
J 0
(2450 2975);
PAINT MONO (2450 2975);
DISPLAY INVISIBLE (2450 2975);
FORCEPROP 2 LAST CDS_LIB mstr_discrete
J 0
(2400 2825);
PAINT MONO (2400 2825);
DISPLAY INVISIBLE (2400 2825);
FORCEPROP 0 LAST CDS_SEC 1
J 0
(2450 2975);
PAINT MONO (2450 2975);
DISPLAY INVISIBLE (2450 2975);
FORCEPROP 1 LAST PATH I301
J 0
(2450 2975);
DISPLAY 0.978723 (2450 2975);
PAINT WHITE (2450 2975);
DISPLAY INVISIBLE (2450 2975);
FORCEADD CAP..1
(4250 2825);
FORCEPROP 1 LASTPIN (4250 2725) $PN 2
J 0
(4260 2705);
DISPLAY 0.617021 (4260 2705);
PAINT ORANGE (4260 2705);
FORCEPROP 1 LAST LOCATION C8L11
J 0
(4300 2925);
DISPLAY 0.617021 (4300 2925);
PAINT AQUA (4300 2925);
FORCEPROP 1 LAST VALUE 100UF
J 0
(4300 2875);
DISPLAY 0.617021 (4300 2875);
PAINT SKYBLUE (4300 2875);
FORCEPROP 1 LAST VOLTAGE 4V
J 0
(4300 2825);
DISPLAY 0.617021 (4300 2825);
PAINT SKYBLUE (4300 2825);
FORCEPROP 1 LAST TOLERANCE 20%
J 0
(4300 2775);
DISPLAY 0.617021 (4300 2775);
PAINT SKYBLUE (4300 2775);
FORCEPROP 1 LAST PACK_TYPE 0805
J 0
(4300 2675);
DISPLAY 0.617021 (4300 2675);
PAINT SKYBLUE (4300 2675);
FORCEPROP 1 LASTPIN (4250 2925) $PN 1
J 0
(4260 2905);
DISPLAY 0.617021 (4260 2905);
PAINT ORANGE (4260 2905);
FORCEPROP 1 LAST PART_NUMBER 602433-112
J 0
(4300 2725);
DISPLAY 0.617021 (4300 2725);
PAINT BLUE (4300 2725);
FORCEPROP 0 LAST BOM_SS NOPOP
J 0
(4291 2360);
DISPLAY 0.638298 (4291 2360);
PAINT BROWN (4291 2360);
DISPLAY BOTH (4291 2360);
FORCEPROP 0 LAST NEW_MATERIAL X6S
J 0
(4300 2400);
DISPLAY 0.638298 (4300 2400);
PAINT BROWN (4300 2400);
DISPLAY BOTH (4300 2400);
FORCEPROP 0 LAST GROUP PWR_MLCC_CAP
J 0
(4306 2312);
DISPLAY 0.638298 (4306 2312);
PAINT BROWN (4306 2312);
DISPLAY BOTH (4306 2312);
FORCEPROP 0 LAST NEW_PN 078.1071T.M002
J 0
(4304 2440);
DISPLAY 0.638298 (4304 2440);
PAINT BROWN (4304 2440);
DISPLAY BOTH (4304 2440);
FORCEPROP 2 LAST CDS_LOCATION C8L11
J 0
(4300 2925);
DISPLAY 0.617021 (4300 2925);
PAINT AQUA (4300 2925);
DISPLAY INVISIBLE (4300 2925);
FORCEPROP 0 LAST CDS_SEC 1
J 0
(4300 2975);
PAINT MONO (4300 2975);
DISPLAY INVISIBLE (4300 2975);
FORCEPROP 2 LAST CDS_LIB mstr_discrete
J 0
(4250 2825);
PAINT MONO (4250 2825);
DISPLAY INVISIBLE (4250 2825);
FORCEPROP 2 LAST BOM_COST MEM_VRD_PVDDQ_CD
J 0
(4300 2975);
PAINT MONO (4300 2975);
DISPLAY INVISIBLE (4300 2975);
FORCEPROP 2 LAST ROOM VDDQ_ABC_PWR_VR
J 0
(4300 2975);
PAINT MONO (4300 2975);
DISPLAY INVISIBLE (4300 2975);
FORCEPROP 2 LAST SEC_TYPE 0805
J 0
(4300 3025);
DISPLAY 1.021277 (4300 3025);
PAINT ORANGE (4300 3025);
DISPLAY INVISIBLE (4300 3025);
FORCEPROP 2 LAST SEC 1
J 0
(4300 3025);
DISPLAY 0.680851 (4300 3025);
PAINT MONO (4300 3025);
DISPLAY INVISIBLE (4300 3025);
FORCEPROP 1 LAST MATERIAL X5R
J 0
(4300 2725);
DISPLAY 0.617021 (4300 2725);
PAINT SKYBLUE (4300 2725);
DISPLAY INVISIBLE (4300 2725);
FORCEPROP 1 LAST PATH I302
J 0
(4300 2975);
DISPLAY 0.978723 (4300 2975);
PAINT WHITE (4300 2975);
DISPLAY INVISIBLE (4300 2975);
FORCEADD CAP..1
(-2325 2975);
FORCEPROP 1 LAST LOCATION C8P2
J 0
(-2275 3075);
DISPLAY 0.617021 (-2275 3075);
PAINT AQUA (-2275 3075);
FORCEPROP 1 LAST PACK_TYPE 0805
J 0
(-2275 2825);
DISPLAY 0.617021 (-2275 2825);
PAINT SKYBLUE (-2275 2825);
FORCEPROP 1 LAST VALUE 100UF
J 0
(-2275 3025);
DISPLAY 0.617021 (-2275 3025);
PAINT SKYBLUE (-2275 3025);
FORCEPROP 1 LAST VOLTAGE 4V
J 0
(-2275 2975);
DISPLAY 0.617021 (-2275 2975);
PAINT SKYBLUE (-2275 2975);
FORCEPROP 1 LAST TOLERANCE 20%
J 0
(-2275 2925);
DISPLAY 0.617021 (-2275 2925);
PAINT SKYBLUE (-2275 2925);
FORCEPROP 1 LASTPIN (-2325 2875) $PN 2
J 0
(-2315 2855);
DISPLAY 0.617021 (-2315 2855);
PAINT ORANGE (-2315 2855);
FORCEPROP 1 LASTPIN (-2325 3075) $PN 1
J 0
(-2315 3055);
DISPLAY 0.617021 (-2315 3055);
PAINT ORANGE (-2315 3055);
FORCEPROP 0 LAST BOM_SS NOPOP
J 0
(-2274 2646);
DISPLAY 0.638298 (-2274 2646);
PAINT BROWN (-2274 2646);
DISPLAY BOTH (-2274 2646);
FORCEPROP 1 LAST PART_NUMBER 602433-112
J 0
(-2275 2875);
DISPLAY 0.617021 (-2275 2875);
PAINT BLUE (-2275 2875);
FORCEPROP 0 LAST GROUP PWR_MLCC_CAP
J 0
(-2269 2687);
DISPLAY 0.638298 (-2269 2687);
PAINT BROWN (-2269 2687);
DISPLAY BOTH (-2269 2687);
FORCEPROP 0 LAST NEW_MATERIAL X6S
J 0
(-2275 2725);
DISPLAY 0.638298 (-2275 2725);
PAINT BROWN (-2275 2725);
DISPLAY BOTH (-2275 2725);
FORCEPROP 0 LAST NEW_PN 078.1071T.M002
J 0
(-2278 2767);
DISPLAY 0.638298 (-2278 2767);
PAINT BROWN (-2278 2767);
DISPLAY BOTH (-2278 2767);
FORCEPROP 2 LAST CDS_LOCATION C8P2
J 0
(-2275 3075);
DISPLAY 0.617021 (-2275 3075);
PAINT AQUA (-2275 3075);
DISPLAY INVISIBLE (-2275 3075);
FORCEPROP 1 LAST PATH I303
J 0
(-2275 3125);
DISPLAY 0.978723 (-2275 3125);
PAINT WHITE (-2275 3125);
DISPLAY INVISIBLE (-2275 3125);
FORCEPROP 1 LAST MATERIAL X5R
J 0
(-2275 2875);
DISPLAY 0.617021 (-2275 2875);
PAINT SKYBLUE (-2275 2875);
DISPLAY INVISIBLE (-2275 2875);
FORCEPROP 2 LAST SEC 1
J 0
(-2275 3175);
DISPLAY 0.680851 (-2275 3175);
PAINT MONO (-2275 3175);
DISPLAY INVISIBLE (-2275 3175);
FORCEPROP 2 LAST SEC_TYPE 0805
J 0
(-2275 3175);
DISPLAY 1.021277 (-2275 3175);
PAINT ORANGE (-2275 3175);
DISPLAY INVISIBLE (-2275 3175);
FORCEPROP 2 LAST ROOM VDDQ_ABC_PWR_VR
J 0
(-2275 3125);
PAINT MONO (-2275 3125);
DISPLAY INVISIBLE (-2275 3125);
FORCEPROP 2 LAST BOM_COST MEM_VRD_PVDDQ_CD
J 0
(-2275 3125);
PAINT MONO (-2275 3125);
DISPLAY INVISIBLE (-2275 3125);
FORCEPROP 2 LAST CDS_LIB mstr_discrete
J 0
(-2325 2975);
PAINT MONO (-2325 2975);
DISPLAY INVISIBLE (-2325 2975);
FORCEPROP 0 LAST CDS_SEC 1
J 0
(-2275 3125);
PAINT MONO (-2275 3125);
DISPLAY INVISIBLE (-2275 3125);
FORCEADD CAP..1
(-1925 2975);
FORCEPROP 1 LAST LOCATION C8P1
J 0
(-1875 3075);
DISPLAY 0.617021 (-1875 3075);
PAINT AQUA (-1875 3075);
FORCEPROP 1 LASTPIN (-1925 3075) $PN 1
J 0
(-1915 3055);
DISPLAY 0.617021 (-1915 3055);
PAINT ORANGE (-1915 3055);
FORCEPROP 1 LASTPIN (-1925 2875) $PN 2
J 0
(-1915 2855);
DISPLAY 0.617021 (-1915 2855);
PAINT ORANGE (-1915 2855);
FORCEPROP 1 LAST VOLTAGE 4V
J 0
(-1875 2975);
DISPLAY 0.617021 (-1875 2975);
PAINT SKYBLUE (-1875 2975);
FORCEPROP 0 LAST BOM_SS NOPOP
J 0
(-1874 2521);
DISPLAY 0.638298 (-1874 2521);
PAINT BROWN (-1874 2521);
DISPLAY BOTH (-1874 2521);
FORCEPROP 0 LAST GROUP PWR_MLCC_CAP
J 0
(-1869 2562);
DISPLAY 0.638298 (-1869 2562);
PAINT BROWN (-1869 2562);
DISPLAY BOTH (-1869 2562);
FORCEPROP 0 LAST NEW_MATERIAL X6S
J 0
(-1875 2600);
DISPLAY 0.638298 (-1875 2600);
PAINT BROWN (-1875 2600);
DISPLAY BOTH (-1875 2600);
FORCEPROP 1 LAST PACK_TYPE 0805
J 0
(-1875 2825);
DISPLAY 0.617021 (-1875 2825);
PAINT SKYBLUE (-1875 2825);
FORCEPROP 1 LAST PART_NUMBER 602433-112
J 0
(-1875 2875);
DISPLAY 0.617021 (-1875 2875);
PAINT BLUE (-1875 2875);
FORCEPROP 1 LAST TOLERANCE 20%
J 0
(-1875 2925);
DISPLAY 0.617021 (-1875 2925);
PAINT SKYBLUE (-1875 2925);
FORCEPROP 1 LAST VALUE 100UF
J 0
(-1875 3025);
DISPLAY 0.617021 (-1875 3025);
PAINT SKYBLUE (-1875 3025);
FORCEPROP 0 LAST NEW_PN 078.1071T.M002
J 0
(-1880 2652);
DISPLAY 0.638298 (-1880 2652);
PAINT BROWN (-1880 2652);
DISPLAY BOTH (-1880 2652);
FORCEPROP 2 LAST CDS_LOCATION C8P1
J 0
(-1875 3075);
DISPLAY 0.617021 (-1875 3075);
PAINT AQUA (-1875 3075);
DISPLAY INVISIBLE (-1875 3075);
FORCEPROP 1 LAST PATH I304
J 0
(-1875 3125);
DISPLAY 0.978723 (-1875 3125);
PAINT WHITE (-1875 3125);
DISPLAY INVISIBLE (-1875 3125);
FORCEPROP 0 LAST CDS_SEC 1
J 0
(-1875 3125);
PAINT MONO (-1875 3125);
DISPLAY INVISIBLE (-1875 3125);
FORCEPROP 2 LAST CDS_LIB mstr_discrete
J 0
(-1925 2975);
PAINT MONO (-1925 2975);
DISPLAY INVISIBLE (-1925 2975);
FORCEPROP 2 LAST BOM_COST MEM_VRD_PVDDQ_CD
J 0
(-1875 3125);
PAINT MONO (-1875 3125);
DISPLAY INVISIBLE (-1875 3125);
FORCEPROP 2 LAST ROOM VDDQ_ABC_PWR_VR
J 0
(-1875 3125);
PAINT MONO (-1875 3125);
DISPLAY INVISIBLE (-1875 3125);
FORCEPROP 2 LAST SEC_TYPE 0805
J 0
(-1875 3175);
DISPLAY 1.021277 (-1875 3175);
PAINT ORANGE (-1875 3175);
DISPLAY INVISIBLE (-1875 3175);
FORCEPROP 2 LAST SEC 1
J 0
(-1875 3175);
DISPLAY 0.680851 (-1875 3175);
PAINT MONO (-1875 3175);
DISPLAY INVISIBLE (-1875 3175);
FORCEPROP 1 LAST MATERIAL X5R
J 0
(-1875 2875);
DISPLAY 0.617021 (-1875 2875);
PAINT SKYBLUE (-1875 2875);
DISPLAY INVISIBLE (-1875 2875);
FORCEADD CAP..1
(1625 2775);
FORCEPROP 1 LAST LOCATION C7P2
J 0
(1675 2875);
DISPLAY 0.617021 (1675 2875);
PAINT AQUA (1675 2875);
FORCEPROP 1 LASTPIN (1625 2875) $PN 1
J 0
(1635 2855);
DISPLAY 0.617021 (1635 2855);
PAINT ORANGE (1635 2855);
FORCEPROP 1 LASTPIN (1625 2675) $PN 2
J 0
(1635 2655);
DISPLAY 0.617021 (1635 2655);
PAINT ORANGE (1635 2655);
FORCEPROP 1 LAST TOLERANCE 20%
J 0
(1675 2725);
DISPLAY 0.617021 (1675 2725);
PAINT SKYBLUE (1675 2725);
FORCEPROP 1 LAST VOLTAGE 4V
J 0
(1675 2775);
DISPLAY 0.617021 (1675 2775);
PAINT SKYBLUE (1675 2775);
FORCEPROP 1 LAST VALUE 100UF
J 0
(1675 2825);
DISPLAY 0.617021 (1675 2825);
PAINT SKYBLUE (1675 2825);
FORCEPROP 0 LAST NEW_MATERIAL X6S
J 0
(1675 2525);
DISPLAY 0.638298 (1675 2525);
PAINT BROWN (1675 2525);
DISPLAY BOTH (1675 2525);
FORCEPROP 1 LAST PACK_TYPE 0805
J 0
(1675 2625);
DISPLAY 0.617021 (1675 2625);
PAINT SKYBLUE (1675 2625);
FORCEPROP 1 LAST PART_NUMBER 602433-112
J 0
(1675 2675);
DISPLAY 0.617021 (1675 2675);
PAINT BLUE (1675 2675);
FORCEPROP 0 LAST BOM_SS NOPOP
J 0
(1676 2396);
DISPLAY 0.638298 (1676 2396);
PAINT BROWN (1676 2396);
DISPLAY BOTH (1676 2396);
FORCEPROP 0 LAST GROUP PWR_MLCC_CAP
J 0
(1656 2462);
DISPLAY 0.638298 (1656 2462);
PAINT BROWN (1656 2462);
DISPLAY BOTH (1656 2462);
FORCEPROP 0 LAST NEW_PN 078.1071T.M002
J 0
(1662 2585);
DISPLAY 0.638298 (1662 2585);
PAINT BROWN (1662 2585);
DISPLAY BOTH (1662 2585);
FORCEPROP 2 LAST CDS_LOCATION C7P2
J 0
(1675 2875);
DISPLAY 0.617021 (1675 2875);
PAINT AQUA (1675 2875);
DISPLAY INVISIBLE (1675 2875);
FORCEPROP 1 LAST PATH I305
J 0
(1675 2925);
DISPLAY 0.978723 (1675 2925);
PAINT WHITE (1675 2925);
DISPLAY INVISIBLE (1675 2925);
FORCEPROP 0 LAST CDS_SEC 1
J 0
(1675 2925);
PAINT MONO (1675 2925);
DISPLAY INVISIBLE (1675 2925);
FORCEPROP 2 LAST CDS_LIB mstr_discrete
J 0
(1625 2775);
PAINT MONO (1625 2775);
DISPLAY INVISIBLE (1625 2775);
FORCEPROP 2 LAST BOM_COST MEM_VRD_PVDDQ_CD
J 0
(1675 2925);
PAINT MONO (1675 2925);
DISPLAY INVISIBLE (1675 2925);
FORCEPROP 2 LAST ROOM VDDQ_ABC_PWR_VR
J 0
(1675 2925);
PAINT MONO (1675 2925);
DISPLAY INVISIBLE (1675 2925);
FORCEPROP 2 LAST SEC_TYPE 0805
J 0
(1675 2975);
DISPLAY 1.021277 (1675 2975);
PAINT ORANGE (1675 2975);
DISPLAY INVISIBLE (1675 2975);
FORCEPROP 2 LAST SEC 1
J 0
(1675 2975);
DISPLAY 0.680851 (1675 2975);
PAINT MONO (1675 2975);
DISPLAY INVISIBLE (1675 2975);
FORCEPROP 1 LAST MATERIAL X5R
J 0
(1675 2675);
DISPLAY 0.617021 (1675 2675);
PAINT SKYBLUE (1675 2675);
DISPLAY INVISIBLE (1675 2675);
FORCEADD CAP..1
(1125 2775);
FORCEPROP 1 LASTPIN (1125 2675) $PN 2
J 0
(1135 2655);
DISPLAY 0.787234 (1135 2655);
PAINT ORANGE (1135 2655);
FORCEPROP 1 LASTPIN (1125 2875) $PN 1
J 0
(1135 2855);
DISPLAY 0.787234 (1135 2855);
PAINT ORANGE (1135 2855);
FORCEPROP 1 LAST LOCATION C8P3
J 0
(1175 2875);
DISPLAY 0.617021 (1175 2875);
PAINT AQUA (1175 2875);
FORCEPROP 1 LAST VALUE 100UF
J 0
(1175 2825);
DISPLAY 0.617021 (1175 2825);
PAINT SKYBLUE (1175 2825);
FORCEPROP 1 LAST VOLTAGE 4V
J 0
(1175 2775);
DISPLAY 0.617021 (1175 2775);
PAINT SKYBLUE (1175 2775);
FORCEPROP 1 LAST PACK_TYPE 0805
J 0
(1175 2625);
DISPLAY 0.617021 (1175 2625);
PAINT SKYBLUE (1175 2625);
FORCEPROP 1 LAST PART_NUMBER 602433-112
J 0
(1175 2675);
DISPLAY 0.617021 (1175 2675);
PAINT BLUE (1175 2675);
FORCEPROP 0 LAST BOM_SS NOPOP
J 0
(1201 2346);
DISPLAY 0.638298 (1201 2346);
PAINT BROWN (1201 2346);
DISPLAY BOTH (1201 2346);
FORCEPROP 0 LAST GROUP PWR_MLCC_CAP
J 0
(1181 2437);
DISPLAY 0.638298 (1181 2437);
PAINT BROWN (1181 2437);
DISPLAY BOTH (1181 2437);
FORCEPROP 0 LAST NEW_MATERIAL X6S
J 0
(1175 2525);
DISPLAY 0.638298 (1175 2525);
PAINT BROWN (1175 2525);
DISPLAY BOTH (1175 2525);
FORCEPROP 0 LAST NEW_PN 078.1071T.M002
J 0
(1162 2560);
DISPLAY 0.638298 (1162 2560);
PAINT BROWN (1162 2560);
DISPLAY BOTH (1162 2560);
FORCEPROP 1 LAST TOLERANCE 20%
J 0
(1175 2725);
DISPLAY 0.617021 (1175 2725);
PAINT SKYBLUE (1175 2725);
FORCEPROP 1 LAST PATH I306
J 0
(1175 2925);
DISPLAY 0.978723 (1175 2925);
PAINT WHITE (1175 2925);
DISPLAY INVISIBLE (1175 2925);
FORCEPROP 2 LAST CDS_LIB mstr_discrete
J 0
(1125 2775);
DISPLAY INVISIBLE (1125 2775);
FORCEPROP 1 LAST MATERIAL X5R
J 0
(1175 2675);
DISPLAY 0.617021 (1175 2675);
PAINT SKYBLUE (1175 2675);
DISPLAY INVISIBLE (1175 2675);
FORCEPROP 2 LAST ROOM VDDQ_ABC_PWR_VR
J 0
(1175 2925);
PAINT MONO (1175 2925);
DISPLAY INVISIBLE (1175 2925);
FORCEPROP 2 LAST BOM_COST MEM_VRD_PVDDQ_CD
J 0
(1175 2925);
PAINT MONO (1175 2925);
DISPLAY INVISIBLE (1175 2925);
FORCEPROP 2 LAST SEC_TYPE 0805
J 0
(1175 2975);
DISPLAY 1.021277 (1175 2975);
PAINT ORANGE (1175 2975);
DISPLAY INVISIBLE (1175 2975);
FORCEPROP 2 LAST SEC 1
J 0
(1175 2975);
DISPLAY 0.680851 (1175 2975);
PAINT MONO (1175 2975);
DISPLAY INVISIBLE (1175 2975);
FORCEADD CAP..1
(650 2775);
FORCEPROP 1 LAST TOLERANCE 20%
J 0
(700 2725);
DISPLAY 0.617021 (700 2725);
PAINT SKYBLUE (700 2725);
FORCEPROP 1 LAST VOLTAGE 4V
J 0
(700 2775);
DISPLAY 0.617021 (700 2775);
PAINT SKYBLUE (700 2775);
FORCEPROP 1 LAST VALUE 100UF
J 0
(700 2825);
DISPLAY 0.617021 (700 2825);
PAINT SKYBLUE (700 2825);
FORCEPROP 1 LAST LOCATION C8P4
J 0
(700 2875);
DISPLAY 0.617021 (700 2875);
PAINT AQUA (700 2875);
FORCEPROP 1 LASTPIN (650 2875) $PN 1
J 0
(660 2855);
DISPLAY 0.787234 (660 2855);
PAINT ORANGE (660 2855);
FORCEPROP 1 LAST PACK_TYPE 0805
J 0
(700 2625);
DISPLAY 0.617021 (700 2625);
PAINT SKYBLUE (700 2625);
FORCEPROP 1 LAST PART_NUMBER 602433-112
J 0
(700 2675);
DISPLAY 0.617021 (700 2675);
PAINT BLUE (700 2675);
FORCEPROP 0 LAST BOM_SS NOPOP
J 0
(726 2421);
DISPLAY 0.638298 (726 2421);
PAINT BROWN (726 2421);
DISPLAY BOTH (726 2421);
FORCEPROP 1 LASTPIN (650 2675) $PN 2
J 0
(660 2655);
DISPLAY 0.787234 (660 2655);
PAINT ORANGE (660 2655);
FORCEPROP 0 LAST NEW_MATERIAL X6S
J 0
(700 2525);
DISPLAY 0.638298 (700 2525);
PAINT BROWN (700 2525);
DISPLAY BOTH (700 2525);
FORCEPROP 0 LAST GROUP PWR_MLCC_CAP
J 0
(706 2462);
DISPLAY 0.638298 (706 2462);
PAINT BROWN (706 2462);
DISPLAY BOTH (706 2462);
FORCEPROP 0 LAST NEW_PN 078.1071T.M002
J 0
(712 2585);
DISPLAY 0.638298 (712 2585);
PAINT BROWN (712 2585);
DISPLAY BOTH (712 2585);
FORCEPROP 2 LAST CDS_LIB mstr_discrete
J 0
(650 2775);
DISPLAY INVISIBLE (650 2775);
FORCEPROP 1 LAST MATERIAL X5R
J 0
(700 2675);
DISPLAY 0.617021 (700 2675);
PAINT SKYBLUE (700 2675);
DISPLAY INVISIBLE (700 2675);
FORCEPROP 2 LAST ROOM VDDQ_ABC_PWR_VR
J 0
(700 2925);
PAINT MONO (700 2925);
DISPLAY INVISIBLE (700 2925);
FORCEPROP 2 LAST BOM_COST MEM_VRD_PVDDQ_CD
J 0
(700 2925);
PAINT MONO (700 2925);
DISPLAY INVISIBLE (700 2925);
FORCEPROP 2 LAST SEC_TYPE 0805
J 0
(700 2975);
DISPLAY 1.021277 (700 2975);
PAINT ORANGE (700 2975);
DISPLAY INVISIBLE (700 2975);
FORCEPROP 2 LAST SEC 1
J 0
(700 2975);
DISPLAY 0.680851 (700 2975);
PAINT MONO (700 2975);
DISPLAY INVISIBLE (700 2975);
FORCEPROP 1 LAST PATH I307
J 0
(700 2925);
DISPLAY 0.978723 (700 2925);
PAINT WHITE (700 2925);
DISPLAY INVISIBLE (700 2925);
FORCEADD CAP..1
(525 725);
FORCEPROP 1 LASTPIN (525 825) $PN 1
J 0
(535 805);
DISPLAY 0.617021 (535 805);
PAINT ORANGE (535 805);
FORCEPROP 1 LASTPIN (525 625) $PN 2
J 0
(535 605);
DISPLAY 0.617021 (535 605);
PAINT ORANGE (535 605);
FORCEPROP 1 LAST TOLERANCE 20%
J 0
(575 675);
DISPLAY 0.617021 (575 675);
PAINT SKYBLUE (575 675);
FORCEPROP 1 LAST LOCATION C7P1
J 0
(575 825);
DISPLAY 0.617021 (575 825);
PAINT AQUA (575 825);
FORCEPROP 1 LAST VALUE 100UF
J 0
(575 775);
DISPLAY 0.617021 (575 775);
PAINT SKYBLUE (575 775);
FORCEPROP 0 LAST BOM_SS NOPOP
J 0
(601 896);
DISPLAY 0.638298 (601 896);
PAINT BROWN (601 896);
DISPLAY BOTH (601 896);
FORCEPROP 0 LAST NEW_MATERIAL X6S
J 0
(575 475);
DISPLAY 0.638298 (575 475);
PAINT BROWN (575 475);
DISPLAY BOTH (575 475);
FORCEPROP 1 LAST PACK_TYPE 0805
J 0
(575 575);
DISPLAY 0.617021 (575 575);
PAINT SKYBLUE (575 575);
FORCEPROP 1 LAST PART_NUMBER 602433-112
J 0
(575 625);
DISPLAY 0.617021 (575 625);
PAINT BLUE (575 625);
FORCEPROP 1 LAST VOLTAGE 4V
J 0
(575 725);
DISPLAY 0.617021 (575 725);
PAINT SKYBLUE (575 725);
FORCEPROP 0 LAST GROUP PWR_MLCC_CAP
J 0
(806 587);
DISPLAY 0.638298 (806 587);
PAINT BROWN (806 587);
DISPLAY BOTH (806 587);
FORCEPROP 0 LAST NEW_PN 078.1071T.M002
J 0
(587 535);
DISPLAY 0.638298 (587 535);
PAINT BROWN (587 535);
DISPLAY BOTH (587 535);
FORCEPROP 2 LAST CDS_LOCATION C7P1
J 0
(575 825);
DISPLAY 0.617021 (575 825);
PAINT AQUA (575 825);
DISPLAY INVISIBLE (575 825);
FORCEPROP 0 LAST CDS_SEC 1
J 0
(575 875);
PAINT MONO (575 875);
DISPLAY INVISIBLE (575 875);
FORCEPROP 2 LAST CDS_LIB mstr_discrete
J 0
(525 725);
PAINT MONO (525 725);
DISPLAY INVISIBLE (525 725);
FORCEPROP 2 LAST BOM_COST MEM_VRD_PVDDQ_CD
J 0
(575 875);
PAINT MONO (575 875);
DISPLAY INVISIBLE (575 875);
FORCEPROP 2 LAST ROOM VDDQ_ABC_PWR_VR
J 0
(575 875);
PAINT MONO (575 875);
DISPLAY INVISIBLE (575 875);
FORCEPROP 2 LAST SEC_TYPE 0805
J 0
(575 925);
DISPLAY 1.021277 (575 925);
PAINT ORANGE (575 925);
DISPLAY INVISIBLE (575 925);
FORCEPROP 2 LAST SEC 1
J 0
(575 925);
DISPLAY 0.680851 (575 925);
PAINT MONO (575 925);
DISPLAY INVISIBLE (575 925);
FORCEPROP 1 LAST MATERIAL X5R
J 0
(575 625);
DISPLAY 0.617021 (575 625);
PAINT SKYBLUE (575 625);
DISPLAY INVISIBLE (575 625);
FORCEPROP 1 LAST PATH I308
J 0
(575 875);
DISPLAY 0.978723 (575 875);
PAINT WHITE (575 875);
DISPLAY INVISIBLE (575 875);
FORCEADD CAP..1
(4950 2825);
FORCEPROP 1 LAST PACK_TYPE 0805
J 0
(5000 2675);
DISPLAY 0.617021 (5000 2675);
PAINT SKYBLUE (5000 2675);
FORCEPROP 1 LAST VALUE 100UF
J 0
(5000 2875);
DISPLAY 0.617021 (5000 2875);
PAINT SKYBLUE (5000 2875);
FORCEPROP 1 LAST VOLTAGE 4V
J 0
(5000 2825);
DISPLAY 0.617021 (5000 2825);
PAINT SKYBLUE (5000 2825);
FORCEPROP 1 LAST TOLERANCE 20%
J 0
(5000 2775);
DISPLAY 0.617021 (5000 2775);
PAINT SKYBLUE (5000 2775);
FORCEPROP 1 LASTPIN (4950 2925) $PN 1
J 0
(4960 2905);
DISPLAY 0.617021 (4960 2905);
PAINT ORANGE (4960 2905);
FORCEPROP 1 LASTPIN (4950 2725) $PN 2
J 0
(4960 2705);
DISPLAY 0.617021 (4960 2705);
PAINT ORANGE (4960 2705);
FORCEPROP 1 LAST PART_NUMBER 602433-112
J 0
(5000 2725);
DISPLAY 0.617021 (5000 2725);
PAINT BLUE (5000 2725);
FORCEPROP 1 LAST LOCATION C2A8
J 0
(5000 2925);
DISPLAY 0.617021 (5000 2925);
PAINT AQUA (5000 2925);
FORCEPROP 0 LAST GROUP PWR_MLCC_CAP
J 0
(4981 2312);
DISPLAY 0.638298 (4981 2312);
PAINT BROWN (4981 2312);
DISPLAY BOTH (4981 2312);
FORCEPROP 0 LAST BOM_SS NOPOP
J 0
(4991 2360);
DISPLAY 0.638298 (4991 2360);
PAINT BROWN (4991 2360);
DISPLAY BOTH (4991 2360);
FORCEPROP 0 LAST NEW_MATERIAL X6S
J 0
(5000 2400);
DISPLAY 0.638298 (5000 2400);
PAINT BROWN (5000 2400);
DISPLAY BOTH (5000 2400);
FORCEPROP 0 LAST NEW_PN 078.1071T.M002
J 0
(5012 2460);
DISPLAY 0.638298 (5012 2460);
PAINT BROWN (5012 2460);
DISPLAY BOTH (5012 2460);
FORCEPROP 2 LAST CDS_LOCATION C2A8
J 0
(5000 2925);
DISPLAY 0.617021 (5000 2925);
PAINT AQUA (5000 2925);
DISPLAY INVISIBLE (5000 2925);
FORCEPROP 1 LAST PATH I309
J 0
(5000 2975);
DISPLAY 0.978723 (5000 2975);
PAINT WHITE (5000 2975);
DISPLAY INVISIBLE (5000 2975);
FORCEPROP 1 LAST MATERIAL X5R
J 0
(5000 2725);
DISPLAY 0.617021 (5000 2725);
PAINT SKYBLUE (5000 2725);
DISPLAY INVISIBLE (5000 2725);
FORCEPROP 2 LAST SEC 1
J 0
(5000 3025);
DISPLAY 0.680851 (5000 3025);
PAINT MONO (5000 3025);
DISPLAY INVISIBLE (5000 3025);
FORCEPROP 2 LAST SEC_TYPE 0805
J 0
(5000 3025);
DISPLAY 1.021277 (5000 3025);
PAINT ORANGE (5000 3025);
DISPLAY INVISIBLE (5000 3025);
FORCEPROP 2 LAST ROOM VDDQ_ABC_PWR_VR
J 0
(5000 2975);
PAINT MONO (5000 2975);
DISPLAY INVISIBLE (5000 2975);
FORCEPROP 2 LAST BOM_COST MEM_VRD_PVDDQ_CD
J 0
(5000 2975);
PAINT MONO (5000 2975);
DISPLAY INVISIBLE (5000 2975);
FORCEPROP 2 LAST CDS_LIB mstr_discrete
J 0
(4950 2825);
PAINT MONO (4950 2825);
DISPLAY INVISIBLE (4950 2825);
FORCEPROP 0 LAST CDS_SEC 1
J 0
(5000 2975);
PAINT MONO (5000 2975);
DISPLAY INVISIBLE (5000 2975);
FORCEADD CAP..1
(4600 2825);
FORCEPROP 1 LAST LOCATION C8L2
J 0
(4650 2925);
DISPLAY 0.617021 (4650 2925);
PAINT AQUA (4650 2925);
FORCEPROP 1 LAST PACK_TYPE 0805
J 0
(4650 2675);
DISPLAY 0.617021 (4650 2675);
PAINT SKYBLUE (4650 2675);
FORCEPROP 1 LAST PART_NUMBER 602433-112
J 0
(4650 2725);
DISPLAY 0.617021 (4650 2725);
PAINT BLUE (4650 2725);
FORCEPROP 1 LAST TOLERANCE 20%
J 0
(4650 2775);
DISPLAY 0.617021 (4650 2775);
PAINT SKYBLUE (4650 2775);
FORCEPROP 1 LASTPIN (4600 2725) $PN 2
J 0
(4610 2705);
DISPLAY 0.617021 (4610 2705);
PAINT ORANGE (4610 2705);
FORCEPROP 0 LAST BOM_SS NOPOP
J 0
(4641 2535);
DISPLAY 0.638298 (4641 2535);
PAINT BROWN (4641 2535);
DISPLAY BOTH (4641 2535);
FORCEPROP 1 LASTPIN (4600 2925) $PN 1
J 0
(4610 2905);
DISPLAY 0.617021 (4610 2905);
PAINT ORANGE (4610 2905);
FORCEPROP 1 LAST VALUE 100UF
J 0
(4650 2875);
DISPLAY 0.617021 (4650 2875);
PAINT SKYBLUE (4650 2875);
FORCEPROP 1 LAST VOLTAGE 4V
J 0
(4650 2825);
DISPLAY 0.617021 (4650 2825);
PAINT SKYBLUE (4650 2825);
FORCEPROP 0 LAST NEW_PN 078.1071T.M002
J 0
(4654 2623);
DISPLAY 0.638298 (4654 2623);
PAINT BROWN (4654 2623);
DISPLAY BOTH (4654 2623);
FORCEPROP 0 LAST NEW_MATERIAL X6S
J 0
(4650 2575);
DISPLAY 0.638298 (4650 2575);
PAINT BROWN (4650 2575);
DISPLAY BOTH (4650 2575);
FORCEPROP 0 LAST GROUP PWR_MLCC_CAP
J 0
(4656 2487);
DISPLAY 0.638298 (4656 2487);
PAINT BROWN (4656 2487);
DISPLAY BOTH (4656 2487);
FORCEPROP 2 LAST CDS_LOCATION C8L2
J 0
(4650 2925);
DISPLAY 0.617021 (4650 2925);
PAINT AQUA (4650 2925);
DISPLAY INVISIBLE (4650 2925);
FORCEPROP 1 LAST MATERIAL X5R
J 0
(4650 2725);
DISPLAY 0.617021 (4650 2725);
PAINT SKYBLUE (4650 2725);
DISPLAY INVISIBLE (4650 2725);
FORCEPROP 2 LAST SEC 1
J 0
(4650 3025);
DISPLAY 0.680851 (4650 3025);
PAINT MONO (4650 3025);
DISPLAY INVISIBLE (4650 3025);
FORCEPROP 2 LAST SEC_TYPE 0805
J 0
(4650 3025);
DISPLAY 1.021277 (4650 3025);
PAINT ORANGE (4650 3025);
DISPLAY INVISIBLE (4650 3025);
FORCEPROP 2 LAST ROOM VDDQ_ABC_PWR_VR
J 0
(4650 2975);
PAINT MONO (4650 2975);
DISPLAY INVISIBLE (4650 2975);
FORCEPROP 2 LAST BOM_COST MEM_VRD_PVDDQ_CD
J 0
(4650 2975);
PAINT MONO (4650 2975);
DISPLAY INVISIBLE (4650 2975);
FORCEPROP 2 LAST CDS_LIB mstr_discrete
J 0
(4600 2825);
PAINT MONO (4600 2825);
DISPLAY INVISIBLE (4600 2825);
FORCEPROP 0 LAST CDS_SEC 1
J 0
(4650 2975);
PAINT MONO (4650 2975);
DISPLAY INVISIBLE (4650 2975);
FORCEPROP 1 LAST PATH I310
J 0
(4650 2975);
DISPLAY 0.978723 (4650 2975);
PAINT WHITE (4650 2975);
DISPLAY INVISIBLE (4650 2975);
FORCEADD CAP..1
(3150 2825);
FORCEPROP 1 LASTPIN (3150 2925) $PN 1
J 0
(3160 2905);
DISPLAY 0.617021 (3160 2905);
PAINT ORANGE (3160 2905);
FORCEPROP 1 LAST LOCATION C8M11
J 0
(3200 2925);
DISPLAY 0.617021 (3200 2925);
PAINT AQUA (3200 2925);
FORCEPROP 1 LAST VALUE 100UF
J 0
(3200 2875);
DISPLAY 0.617021 (3200 2875);
PAINT SKYBLUE (3200 2875);
FORCEPROP 1 LAST VOLTAGE 4V
J 0
(3200 2825);
DISPLAY 0.617021 (3200 2825);
PAINT SKYBLUE (3200 2825);
FORCEPROP 1 LASTPIN (3150 2725) $PN 2
J 0
(3160 2705);
DISPLAY 0.617021 (3160 2705);
PAINT ORANGE (3160 2705);
FORCEPROP 0 LAST GROUP PWR_MLCC_CAP
J 0
(3206 2487);
DISPLAY 0.638298 (3206 2487);
PAINT BROWN (3206 2487);
DISPLAY BOTH (3206 2487);
FORCEPROP 1 LAST TOLERANCE 20%
J 0
(3200 2775);
DISPLAY 0.617021 (3200 2775);
PAINT SKYBLUE (3200 2775);
FORCEPROP 1 LAST PART_NUMBER 602433-112
J 0
(3200 2725);
DISPLAY 0.617021 (3200 2725);
PAINT BLUE (3200 2725);
FORCEPROP 1 LAST PACK_TYPE 0805
J 0
(3200 2675);
DISPLAY 0.617021 (3200 2675);
PAINT SKYBLUE (3200 2675);
FORCEPROP 0 LAST NEW_MATERIAL X6S
J 0
(3200 2575);
DISPLAY 0.638298 (3200 2575);
PAINT BROWN (3200 2575);
DISPLAY BOTH (3200 2575);
FORCEPROP 0 LAST BOM_SS NOPOP
J 0
(3191 2535);
DISPLAY 0.638298 (3191 2535);
PAINT BROWN (3191 2535);
DISPLAY BOTH (3191 2535);
FORCEPROP 0 LAST NEW_PN 078.1071T.M002
J 0
(3191 2620);
DISPLAY 0.638298 (3191 2620);
PAINT BROWN (3191 2620);
DISPLAY BOTH (3191 2620);
FORCEPROP 2 LAST CDS_LOCATION C8M11
J 0
(3200 2925);
DISPLAY 0.617021 (3200 2925);
PAINT AQUA (3200 2925);
DISPLAY INVISIBLE (3200 2925);
FORCEPROP 0 LAST CDS_SEC 1
J 0
(3200 2975);
PAINT MONO (3200 2975);
DISPLAY INVISIBLE (3200 2975);
FORCEPROP 2 LAST CDS_LIB mstr_discrete
J 0
(3150 2825);
PAINT MONO (3150 2825);
DISPLAY INVISIBLE (3150 2825);
FORCEPROP 2 LAST BOM_COST MEM_VRD_PVDDQ_CD
J 0
(3200 2975);
PAINT MONO (3200 2975);
DISPLAY INVISIBLE (3200 2975);
FORCEPROP 2 LAST ROOM VDDQ_ABC_PWR_VR
J 0
(3200 2975);
PAINT MONO (3200 2975);
DISPLAY INVISIBLE (3200 2975);
FORCEPROP 2 LAST SEC_TYPE 0805
J 0
(3200 3025);
DISPLAY 1.021277 (3200 3025);
PAINT ORANGE (3200 3025);
DISPLAY INVISIBLE (3200 3025);
FORCEPROP 2 LAST SEC 1
J 0
(3200 3025);
DISPLAY 0.680851 (3200 3025);
PAINT MONO (3200 3025);
DISPLAY INVISIBLE (3200 3025);
FORCEPROP 1 LAST MATERIAL X5R
J 0
(3200 2725);
DISPLAY 0.617021 (3200 2725);
PAINT SKYBLUE (3200 2725);
DISPLAY INVISIBLE (3200 2725);
FORCEPROP 1 LAST PATH I311
J 0
(3200 2975);
DISPLAY 0.978723 (3200 2975);
PAINT WHITE (3200 2975);
DISPLAY INVISIBLE (3200 2975);
FORCEADD CAP..1
(3500 2825);
FORCEPROP 1 LAST PART_NUMBER 602433-112
J 0
(3550 2725);
DISPLAY 0.617021 (3550 2725);
PAINT BLUE (3550 2725);
FORCEPROP 1 LAST PACK_TYPE 0805
J 0
(3550 2675);
DISPLAY 0.617021 (3550 2675);
PAINT SKYBLUE (3550 2675);
FORCEPROP 1 LAST LOCATION C8M7
J 0
(3550 2925);
DISPLAY 0.617021 (3550 2925);
PAINT AQUA (3550 2925);
FORCEPROP 1 LASTPIN (3500 2725) $PN 2
J 0
(3510 2705);
DISPLAY 0.617021 (3510 2705);
PAINT ORANGE (3510 2705);
FORCEPROP 1 LASTPIN (3500 2925) $PN 1
J 0
(3510 2905);
DISPLAY 0.617021 (3510 2905);
PAINT ORANGE (3510 2905);
FORCEPROP 1 LAST TOLERANCE 20%
J 0
(3550 2775);
DISPLAY 0.617021 (3550 2775);
PAINT SKYBLUE (3550 2775);
FORCEPROP 1 LAST VOLTAGE 4V
J 0
(3550 2825);
DISPLAY 0.617021 (3550 2825);
PAINT SKYBLUE (3550 2825);
FORCEPROP 1 LAST VALUE 100UF
J 0
(3550 2875);
DISPLAY 0.617021 (3550 2875);
PAINT SKYBLUE (3550 2875);
FORCEPROP 0 LAST NEW_MATERIAL X6S
J 0
(3550 2400);
DISPLAY 0.638298 (3550 2400);
PAINT BROWN (3550 2400);
DISPLAY BOTH (3550 2400);
FORCEPROP 0 LAST BOM_SS NOPOP
J 0
(3541 2360);
DISPLAY 0.638298 (3541 2360);
PAINT BROWN (3541 2360);
DISPLAY BOTH (3541 2360);
FORCEPROP 0 LAST GROUP PWR_MLCC_CAP
J 0
(3556 2312);
DISPLAY 0.638298 (3556 2312);
PAINT BROWN (3556 2312);
DISPLAY BOTH (3556 2312);
FORCEPROP 0 LAST NEW_PN 078.1071T.M002
J 0
(3563 2457);
DISPLAY 0.638298 (3563 2457);
PAINT BROWN (3563 2457);
DISPLAY BOTH (3563 2457);
FORCEPROP 2 LAST CDS_LOCATION C8M7
J 0
(3550 2925);
DISPLAY 0.617021 (3550 2925);
PAINT AQUA (3550 2925);
DISPLAY INVISIBLE (3550 2925);
FORCEPROP 1 LAST PATH I312
J 0
(3550 2975);
DISPLAY 0.978723 (3550 2975);
PAINT WHITE (3550 2975);
DISPLAY INVISIBLE (3550 2975);
FORCEPROP 0 LAST CDS_SEC 1
J 0
(3550 2975);
PAINT MONO (3550 2975);
DISPLAY INVISIBLE (3550 2975);
FORCEPROP 2 LAST CDS_LIB mstr_discrete
J 0
(3500 2825);
PAINT MONO (3500 2825);
DISPLAY INVISIBLE (3500 2825);
FORCEPROP 2 LAST BOM_COST MEM_VRD_PVDDQ_CD
J 0
(3550 2975);
PAINT MONO (3550 2975);
DISPLAY INVISIBLE (3550 2975);
FORCEPROP 2 LAST ROOM VDDQ_ABC_PWR_VR
J 0
(3550 2975);
PAINT MONO (3550 2975);
DISPLAY INVISIBLE (3550 2975);
FORCEPROP 2 LAST SEC_TYPE 0805
J 0
(3550 3025);
DISPLAY 1.021277 (3550 3025);
PAINT ORANGE (3550 3025);
DISPLAY INVISIBLE (3550 3025);
FORCEPROP 2 LAST SEC 1
J 0
(3550 3025);
DISPLAY 0.680851 (3550 3025);
PAINT MONO (3550 3025);
DISPLAY INVISIBLE (3550 3025);
FORCEPROP 1 LAST MATERIAL X5R
J 0
(3550 2725);
DISPLAY 0.617021 (3550 2725);
PAINT SKYBLUE (3550 2725);
DISPLAY INVISIBLE (3550 2725);
FORCEADD CAP..1
(3850 2825);
FORCEPROP 1 LAST PART_NUMBER 602433-112
J 0
(3900 2725);
DISPLAY 0.617021 (3900 2725);
PAINT BLUE (3900 2725);
FORCEPROP 1 LASTPIN (3850 2725) $PN 2
J 0
(3860 2705);
DISPLAY 0.617021 (3860 2705);
PAINT ORANGE (3860 2705);
FORCEPROP 1 LAST TOLERANCE 20%
J 0
(3900 2775);
DISPLAY 0.617021 (3900 2775);
PAINT SKYBLUE (3900 2775);
FORCEPROP 1 LAST VOLTAGE 4V
J 0
(3900 2825);
DISPLAY 0.617021 (3900 2825);
PAINT SKYBLUE (3900 2825);
FORCEPROP 1 LAST VALUE 100UF
J 0
(3900 2875);
DISPLAY 0.617021 (3900 2875);
PAINT SKYBLUE (3900 2875);
FORCEPROP 1 LAST LOCATION C2A16
J 0
(3900 2925);
DISPLAY 0.617021 (3900 2925);
PAINT AQUA (3900 2925);
FORCEPROP 1 LASTPIN (3850 2925) $PN 1
J 0
(3860 2905);
DISPLAY 0.617021 (3860 2905);
PAINT ORANGE (3860 2905);
FORCEPROP 0 LAST GROUP PWR_MLCC_CAP
J 0
(3906 2487);
DISPLAY 0.638298 (3906 2487);
PAINT BROWN (3906 2487);
DISPLAY BOTH (3906 2487);
FORCEPROP 0 LAST BOM_SS NOPOP
J 0
(3891 2535);
DISPLAY 0.638298 (3891 2535);
PAINT BROWN (3891 2535);
DISPLAY BOTH (3891 2535);
FORCEPROP 1 LAST PACK_TYPE 0805
J 0
(3900 2675);
DISPLAY 0.617021 (3900 2675);
PAINT SKYBLUE (3900 2675);
FORCEPROP 0 LAST NEW_MATERIAL X6S
J 0
(3900 2575);
DISPLAY 0.638298 (3900 2575);
PAINT BROWN (3900 2575);
DISPLAY BOTH (3900 2575);
FORCEPROP 0 LAST NEW_PN 078.1071T.M002
J 0
(3899 2634);
DISPLAY 0.638298 (3899 2634);
PAINT BROWN (3899 2634);
DISPLAY BOTH (3899 2634);
FORCEPROP 2 LAST CDS_LOCATION C2A16
J 0
(3900 2925);
DISPLAY 0.617021 (3900 2925);
PAINT AQUA (3900 2925);
DISPLAY INVISIBLE (3900 2925);
FORCEPROP 1 LAST PATH I313
J 0
(3900 2975);
DISPLAY 0.978723 (3900 2975);
PAINT WHITE (3900 2975);
DISPLAY INVISIBLE (3900 2975);
FORCEPROP 0 LAST CDS_SEC 1
J 0
(3900 2975);
PAINT MONO (3900 2975);
DISPLAY INVISIBLE (3900 2975);
FORCEPROP 2 LAST CDS_LIB mstr_discrete
J 0
(3850 2825);
PAINT MONO (3850 2825);
DISPLAY INVISIBLE (3850 2825);
FORCEPROP 2 LAST BOM_COST MEM_VRD_PVDDQ_CD
J 0
(3900 2975);
PAINT MONO (3900 2975);
DISPLAY INVISIBLE (3900 2975);
FORCEPROP 2 LAST ROOM VDDQ_ABC_PWR_VR
J 0
(3900 2975);
PAINT MONO (3900 2975);
DISPLAY INVISIBLE (3900 2975);
FORCEPROP 2 LAST SEC_TYPE 0805
J 0
(3900 3025);
DISPLAY 1.021277 (3900 3025);
PAINT ORANGE (3900 3025);
DISPLAY INVISIBLE (3900 3025);
FORCEPROP 2 LAST SEC 1
J 0
(3900 3025);
DISPLAY 0.680851 (3900 3025);
PAINT MONO (3900 3025);
DISPLAY INVISIBLE (3900 3025);
FORCEPROP 1 LAST MATERIAL X5R
J 0
(3900 2725);
DISPLAY 0.617021 (3900 2725);
PAINT SKYBLUE (3900 2725);
DISPLAY INVISIBLE (3900 2725);
FORCEADD CAP..1
(2750 2825);
FORCEPROP 1 LASTPIN (2750 2925) $PN 1
J 0
(2760 2905);
DISPLAY 0.617021 (2760 2905);
PAINT ORANGE (2760 2905);
FORCEPROP 1 LASTPIN (2750 2725) $PN 2
J 0
(2760 2705);
DISPLAY 0.617021 (2760 2705);
PAINT ORANGE (2760 2705);
FORCEPROP 1 LAST PACK_TYPE 0805
J 0
(2800 2675);
DISPLAY 0.617021 (2800 2675);
PAINT SKYBLUE (2800 2675);
FORCEPROP 1 LAST TOLERANCE 20%
J 0
(2800 2775);
DISPLAY 0.617021 (2800 2775);
PAINT SKYBLUE (2800 2775);
FORCEPROP 0 LAST GROUP PWR_MLCC_CAP
J 0
(2806 2337);
DISPLAY 0.638298 (2806 2337);
PAINT BROWN (2806 2337);
DISPLAY BOTH (2806 2337);
FORCEPROP 0 LAST BOM_SS NOPOP
J 0
(2801 2371);
DISPLAY 0.638298 (2801 2371);
PAINT BROWN (2801 2371);
DISPLAY BOTH (2801 2371);
FORCEPROP 0 LAST NEW_MATERIAL X6S
J 0
(2800 2400);
DISPLAY 0.638298 (2800 2400);
PAINT BROWN (2800 2400);
DISPLAY BOTH (2800 2400);
FORCEPROP 1 LAST PART_NUMBER 602433-112
J 0
(2800 2725);
DISPLAY 0.617021 (2800 2725);
PAINT BLUE (2800 2725);
FORCEPROP 1 LAST VOLTAGE 4V
J 0
(2800 2825);
DISPLAY 0.617021 (2800 2825);
PAINT SKYBLUE (2800 2825);
FORCEPROP 1 LAST VALUE 100UF
J 0
(2800 2875);
DISPLAY 0.617021 (2800 2875);
PAINT SKYBLUE (2800 2875);
FORCEPROP 1 LAST LOCATION C7L1
J 0
(2800 2925);
DISPLAY 0.617021 (2800 2925);
PAINT AQUA (2800 2925);
FORCEPROP 0 LAST NEW_PN 078.1071T.M002
J 0
(2801 2437);
DISPLAY 0.638298 (2801 2437);
PAINT BROWN (2801 2437);
DISPLAY BOTH (2801 2437);
FORCEPROP 2 LAST CDS_LOCATION C7L1
J 0
(2800 2925);
DISPLAY 0.617021 (2800 2925);
PAINT AQUA (2800 2925);
DISPLAY INVISIBLE (2800 2925);
FORCEPROP 1 LAST PATH I314
J 0
(2800 2975);
DISPLAY 0.978723 (2800 2975);
PAINT WHITE (2800 2975);
DISPLAY INVISIBLE (2800 2975);
FORCEPROP 1 LAST MATERIAL X5R
J 0
(2800 2725);
DISPLAY 0.617021 (2800 2725);
PAINT SKYBLUE (2800 2725);
DISPLAY INVISIBLE (2800 2725);
FORCEPROP 2 LAST SEC 1
J 0
(2800 3025);
DISPLAY 0.680851 (2800 3025);
PAINT MONO (2800 3025);
DISPLAY INVISIBLE (2800 3025);
FORCEPROP 2 LAST SEC_TYPE 0805
J 0
(2800 3025);
DISPLAY 1.021277 (2800 3025);
PAINT ORANGE (2800 3025);
DISPLAY INVISIBLE (2800 3025);
FORCEPROP 2 LAST ROOM VDDQ_ABC_PWR_VR
J 0
(2800 2975);
PAINT MONO (2800 2975);
DISPLAY INVISIBLE (2800 2975);
FORCEPROP 2 LAST BOM_COST MEM_VRD_PVDDQ_CD
J 0
(2800 2975);
PAINT MONO (2800 2975);
DISPLAY INVISIBLE (2800 2975);
FORCEPROP 2 LAST CDS_LIB mstr_discrete
J 0
(2750 2825);
PAINT MONO (2750 2825);
DISPLAY INVISIBLE (2750 2825);
FORCEPROP 0 LAST CDS_SEC 1
J 0
(2800 2975);
PAINT MONO (2800 2975);
DISPLAY INVISIBLE (2800 2975);
FORCEADD RES..2
(4100 -500);
FORCEPROP 1 LAST LOCATION R1A1
J 0
(4145 -350);
DISPLAY 0.617021 (4145 -350);
PAINT AQUA (4145 -350);
FORCEPROP 1 LAST VALUE 120.0
J 0
(4145 -400);
DISPLAY 0.617021 (4145 -400);
PAINT SKYBLUE (4145 -400);
FORCEPROP 1 LAST TOLERANCE 1%
J 0
(4145 -450);
DISPLAY 0.617021 (4145 -450);
PAINT SKYBLUE (4145 -450);
FORCEPROP 1 LAST WATTAGE 1/10W
J 0
(4140 -500);
DISPLAY 0.617021 (4140 -500);
PAINT SKYBLUE (4140 -500);
FORCEPROP 1 LAST PART_NUMBER G22026-003
J 0
(4140 -600);
DISPLAY 0.617021 (4140 -600);
PAINT BLUE (4140 -600);
FORCEPROP 1 LASTPIN (4100 -400) $PN 1
J 0
(4105 -438);
DISPLAY 0.617021 (4105 -438);
PAINT GREEN (4105 -438);
FORCEPROP 1 LASTPIN (4100 -600) $PN 2
J 0
(4105 -590);
DISPLAY 0.617021 (4105 -590);
PAINT GREEN (4105 -590);
FORCEPROP 1 LAST MATERIAL CHIP
J 0
(4140 -550);
DISPLAY 0.617021 (4140 -550);
PAINT SKYBLUE (4140 -550);
FORCEPROP 1 LAST PACK_TYPE 0603
J 0
(4140 -650);
DISPLAY 0.617021 (4140 -650);
PAINT SKYBLUE (4140 -650);
FORCEPROP 2 LAST CDS_LIB mstr_discrete
J 0
(4100 -500);
PAINT ORANGE (4100 -500);
DISPLAY INVISIBLE (4100 -500);
FORCEPROP 2 LAST ROOM VDDQ_KLM_PWR_VR
J 0
(4150 -325);
PAINT MONO (4150 -325);
DISPLAY INVISIBLE (4150 -325);
FORCEPROP 1 LAST PATH I58
J 0
(4150 -325);
DISPLAY 0.978723 (4150 -325);
PAINT GREEN (4150 -325);
DISPLAY INVISIBLE (4150 -325);
FORCEPROP 2 LAST CDS_LOCATION R1A1
J 0
(4145 -375);
DISPLAY 0.617021 (4145 -375);
PAINT AQUA (4145 -375);
DISPLAY INVISIBLE (4145 -375);
FORCEPROP 2 LAST BOM_COST MEM_VRD_PVPP_AB
J 0
(4150 -325);
PAINT MONO (4150 -325);
DISPLAY INVISIBLE (4150 -325);
FORCEPROP 2 LAST $SEC 1
J 0
(4150 -275);
PAINT MONO (4150 -275);
DISPLAY INVISIBLE (4150 -275);
FORCEPROP 2 LAST CDS_SEC 1
J 0
(4150 -275);
PAINT MONO (4150 -275);
DISPLAY INVISIBLE (4150 -275);
FORCEADD GND..1
(275 1500);
FORCEPROP 3 LASTPIN (275 1550) SIG_NAME GND\g
J 0
(285 1560);
DISPLAY 0.659574 (285 1560);
PAINT MONO (285 1560);
DISPLAY INVISIBLE (285 1560);
FORCEPROP 1 LAST PATH I65
J 0
(350 1500);
DISPLAY 1.170213 (350 1500);
PAINT AQUA (350 1500);
DISPLAY INVISIBLE (350 1500);
FORCEPROP 2 LAST CDS_LIB mstr_symbols
J 0
(275 1500);
PAINT ORANGE (275 1500);
DISPLAY INVISIBLE (275 1500);
FORCEPROP 1 LAST VOLTAGE 0
J 0
(275 1500);
PAINT SKYBLUE (275 1500);
DISPLAY INVISIBLE (275 1500);
FORCEPROP 1 LAST SIZE 1B
J 0
(350 1450);
DISPLAY 0.893617 (350 1450);
PAINT GREEN (350 1450);
DISPLAY INVISIBLE (350 1450);
FORCEPROP 2 LAST BOM_COST MEM_VRD_PVPP_AB
J 0
(-50 1575);
PAINT MONO (-50 1575);
DISPLAY INVISIBLE (-50 1575);
FORCEPROP 2 LAST ROOM VDDQ_KLM_PWR_VR
J 0
(-275 1575);
PAINT ORANGE (-275 1575);
DISPLAY INVISIBLE (-275 1575);
FORCEPROP 1 LAST BODY_TYPE PLUMBING
J 0
(230 1457);
DISPLAY 0.340426 (230 1457);
PAINT GREEN (230 1457);
DISPLAY INVISIBLE (230 1457);
FORCEPROP 1 LAST HDL_POWER GND
J 0
(275 1650);
DISPLAY 0.893617 (275 1650);
PAINT GREEN (275 1650);
DISPLAY INVISIBLE (275 1650);
FORCEADD OFFPAGE..1
(-1625 1800);
FORCEPROP 2 LAST $XR0 226 
J 0
(-1877 1800);
DISPLAY 0.638298 (-1877 1800);
PAINT MONO (-1877 1800);
FORCEPROP 2 LAST CDS_LIB mstr_standard
J 0
(-1625 1800);
PAINT ORANGE (-1625 1800);
DISPLAY INVISIBLE (-1625 1800);
FORCEPROP 2 LAST PATH I70
J 0
(-1555 1870);
DISPLAY 1.361702 (-1555 1870);
PAINT ORANGE (-1555 1870);
DISPLAY INVISIBLE (-1555 1870);
FORCEPROP 2 LAST BOM_COST MEM_VRD_PVPP_AB
J 0
(-1900 1850);
PAINT MONO (-1900 1850);
DISPLAY INVISIBLE (-1900 1850);
FORCEPROP 1 LAST OFFPAGE TRUE
J 0
(-1300 1675);
DISPLAY 0.893617 (-1300 1675);
PAINT GREEN (-1300 1675);
DISPLAY INVISIBLE (-1300 1675);
FORCEPROP 1 LAST COMMENT_BODY TRUE
J 0
(-1500 1700);
DISPLAY 0.893617 (-1500 1700);
PAINT GREEN (-1500 1700);
DISPLAY INVISIBLE (-1500 1700);
FORCEADD OFFPAGE..1
(-1650 2150);
FORCEPROP 2 LAST $XR0 226 
J 0
(-1902 2150);
DISPLAY 0.638298 (-1902 2150);
PAINT MONO (-1902 2150);
FORCEPROP 2 LAST CDS_LIB mstr_standard
J 0
(-1650 2150);
PAINT ORANGE (-1650 2150);
DISPLAY INVISIBLE (-1650 2150);
FORCEPROP 2 LAST PATH I72
J 0
(-1600 2225);
DISPLAY 1.361702 (-1600 2225);
PAINT ORANGE (-1600 2225);
DISPLAY INVISIBLE (-1600 2225);
FORCEPROP 1 LAST OFFPAGE TRUE
J 0
(-1325 2025);
DISPLAY 1.170213 (-1325 2025);
PAINT GREEN (-1325 2025);
DISPLAY INVISIBLE (-1325 2025);
FORCEPROP 1 LAST COMMENT_BODY TRUE
J 0
(-1525 2050);
DISPLAY 1.170213 (-1525 2050);
PAINT GREEN (-1525 2050);
DISPLAY INVISIBLE (-1525 2050);
FORCEADD PVDDQ_KLM..1
(300 2375);
FORCEPROP 3 LASTPIN (300 2325) SIG_NAME PVDDQ_KLM\g
J 0
(310 2335);
DISPLAY 0.659574 (310 2335);
PAINT MONO (310 2335);
DISPLAY INVISIBLE (310 2335);
FORCEPROP 2 LAST ROOM VDDQ_KLM_PWR_VR
J 0
(550 2475);
PAINT ORANGE (550 2475);
DISPLAY INVISIBLE (550 2475);
FORCEPROP 1 LAST PATH I73
J 0
(350 2400);
DISPLAY 0.872340 (350 2400);
PAINT AQUA (350 2400);
DISPLAY INVISIBLE (350 2400);
FORCEPROP 2 LAST BOM_COST MEM_VRD_PVPP_AB
J 0
(325 2475);
PAINT MONO (325 2475);
DISPLAY INVISIBLE (325 2475);
FORCEPROP 2 LAST CDS_LIB mstr_symbols
J 0
(300 2375);
PAINT ORANGE (300 2375);
DISPLAY INVISIBLE (300 2375);
FORCEPROP 1 LAST VOLTAGE 1.2V
J 0
(255 2332);
DISPLAY 0.340426 (255 2332);
PAINT SKYBLUE (255 2332);
DISPLAY INVISIBLE (255 2332);
FORCEPROP 1 LAST BODY_TYPE PLUMBING
J 0
(255 2332);
DISPLAY 0.340426 (255 2332);
PAINT GREEN (255 2332);
DISPLAY INVISIBLE (255 2332);
FORCEPROP 1 LAST HDL_POWER PVDDQ_KLM
J 1
(300 2425);
DISPLAY 0.872340 (300 2425);
PAINT GREEN (300 2425);
DISPLAY INVISIBLE (300 2425);
FORCEADD RES..2
(-375 1925);
FORCEPROP 1 LASTPIN (-375 1825) $PN 2
J 0
(-370 1835);
DISPLAY 0.617021 (-370 1835);
PAINT ORANGE (-370 1835);
FORCEPROP 1 LASTPIN (-375 2025) $PN 1
J 0
(-370 1987);
DISPLAY 0.617021 (-370 1987);
PAINT ORANGE (-370 1987);
FORCEPROP 1 LAST TOLERANCE 1%
J 0
(-330 1950);
DISPLAY 0.617021 (-330 1950);
PAINT SKYBLUE (-330 1950);
FORCEPROP 1 LAST PART_NUMBER G21796-017
J 0
(-335 1800);
DISPLAY 0.617021 (-335 1800);
PAINT BLUE (-335 1800);
FORCEPROP 1 LAST WATTAGE 1/16W
J 0
(-335 1900);
DISPLAY 0.617021 (-335 1900);
PAINT SKYBLUE (-335 1900);
FORCEPROP 1 LAST PACK_TYPE 0402
J 0
(-335 1750);
DISPLAY 0.617021 (-335 1750);
PAINT SKYBLUE (-335 1750);
FORCEPROP 1 LAST MATERIAL EMPTY
J 0
(-335 1850);
DISPLAY 0.617021 (-335 1850);
PAINT RED (-335 1850);
FORCEPROP 1 LAST LOCATION R7L2
J 0
(-330 2050);
DISPLAY 0.617021 (-330 2050);
PAINT AQUA (-330 2050);
FORCEPROP 1 LAST VALUE 100.0
J 0
(-330 2000);
DISPLAY 0.617021 (-330 2000);
PAINT SKYBLUE (-330 2000);
FORCEPROP 2 LAST SEC_TYPE 0402
J 0
(-325 2175);
DISPLAY 1.021277 (-325 2175);
PAINT ORANGE (-325 2175);
DISPLAY INVISIBLE (-325 2175);
FORCEPROP 0 LAST ROOM VDDQ_KLM_PWR_VR
J 0
(-325 2100);
DISPLAY 1.021277 (-325 2100);
PAINT ORANGE (-325 2100);
DISPLAY INVISIBLE (-325 2100);
FORCEPROP 2 LAST SEC 1
J 0
(-325 2175);
DISPLAY 0.680851 (-325 2175);
PAINT MONO (-325 2175);
DISPLAY INVISIBLE (-325 2175);
FORCEPROP 2 LAST CDS_LOCATION R7L2
J 0
(-330 2050);
DISPLAY 0.617021 (-330 2050);
PAINT AQUA (-330 2050);
DISPLAY INVISIBLE (-330 2050);
FORCEPROP 1 LAST PATH I74
J 0
(-325 2100);
DISPLAY 1.319149 (-325 2100);
PAINT WHITE (-325 2100);
DISPLAY INVISIBLE (-325 2100);
FORCEPROP 2 LAST CDS_LIB mstr_discrete
J 0
(-375 1925);
PAINT ORANGE (-375 1925);
DISPLAY INVISIBLE (-375 1925);
FORCEADD CAPP..1
(2900 -500);
FORCEPROP 1 LAST PACK_TYPE 3018
J 0
(2950 -600);
DISPLAY 0.617021 (2950 -600);
PAINT SKYBLUE (2950 -600);
FORCEPROP 1 LAST PART_NUMBER 699013-049
J 0
(2950 -650);
DISPLAY 0.617021 (2950 -650);
PAINT BLUE (2950 -650);
FORCEPROP 1 LAST MATERIAL ALUM
J 0
(2950 -550);
DISPLAY 0.617021 (2950 -550);
PAINT SKYBLUE (2950 -550);
FORCEPROP 1 LAST VOLTAGE 2.5V
J 0
(2950 -500);
DISPLAY 0.617021 (2950 -500);
PAINT SKYBLUE (2950 -500);
FORCEPROP 1 LAST TOLERANCE 20%
J 0
(2950 -450);
DISPLAY 0.617021 (2950 -450);
PAINT SKYBLUE (2950 -450);
FORCEPROP 1 LAST VALUE 470UF
J 0
(2950 -400);
DISPLAY 0.617021 (2950 -400);
PAINT SKYBLUE (2950 -400);
FORCEPROP 1 LAST LOCATION C9L9
J 0
(2950 -350);
DISPLAY 0.617021 (2950 -350);
PAINT AQUA (2950 -350);
FORCEPROP 1 LASTPIN (2900 -400) $PN 1
J 0
(2910 -415);
DISPLAY 0.617021 (2910 -415);
PAINT ORANGE (2910 -415);
FORCEPROP 1 LASTPIN (2900 -600) $PN 2
J 0
(2910 -615);
DISPLAY 0.617021 (2910 -615);
PAINT ORANGE (2910 -615);
FORCEPROP 0 LAST GROUP PWR_BULK_CAP
J 0
(2965 -699);
DISPLAY 0.638298 (2965 -699);
PAINT BROWN (2965 -699);
DISPLAY BOTH (2965 -699);
FORCEPROP 2 LAST CDS_LIB mstr_discrete
J 0
(2900 -500);
PAINT ORANGE (2900 -500);
DISPLAY INVISIBLE (2900 -500);
FORCEPROP 2 LAST CDS_LOCATION C9L9
J 0
(2950 -400);
DISPLAY 0.617021 (2950 -400);
PAINT AQUA (2950 -400);
DISPLAY INVISIBLE (2950 -400);
FORCEPROP 1 LAST PATH I75
J 0
(2950 -350);
DISPLAY 1.319149 (2950 -350);
PAINT ORANGE (2950 -350);
DISPLAY INVISIBLE (2950 -350);
FORCEPROP 0 LAST ROOM VDDQ_KLM_PWR_VR
J 0
(2950 -350);
DISPLAY 1.021277 (2950 -350);
PAINT ORANGE (2950 -350);
DISPLAY INVISIBLE (2950 -350);
FORCEPROP 2 LAST SEC_TYPE 3018
J 0
(2950 -275);
DISPLAY 1.021277 (2950 -275);
PAINT ORANGE (2950 -275);
DISPLAY INVISIBLE (2950 -275);
FORCEPROP 2 LAST SEC 1
J 0
(2950 -275);
DISPLAY 0.680851 (2950 -275);
PAINT MONO (2950 -275);
DISPLAY INVISIBLE (2950 -275);
FORCEADD CAPP..1
(3200 -500);
FORCEPROP 1 LAST VOLTAGE 2.5V
J 0
(3250 -500);
DISPLAY 0.617021 (3250 -500);
PAINT SKYBLUE (3250 -500);
FORCEPROP 1 LAST MATERIAL ALUM
J 0
(3250 -550);
DISPLAY 0.617021 (3250 -550);
PAINT SKYBLUE (3250 -550);
FORCEPROP 1 LAST PACK_TYPE 3018
J 0
(3250 -600);
DISPLAY 0.617021 (3250 -600);
PAINT SKYBLUE (3250 -600);
FORCEPROP 1 LAST PART_NUMBER 699013-049
J 0
(3250 -650);
DISPLAY 0.617021 (3250 -650);
PAINT BLUE (3250 -650);
FORCEPROP 1 LAST TOLERANCE 20%
J 0
(3250 -450);
DISPLAY 0.617021 (3250 -450);
PAINT SKYBLUE (3250 -450);
FORCEPROP 1 LAST VALUE 470UF
J 0
(3250 -400);
DISPLAY 0.617021 (3250 -400);
PAINT SKYBLUE (3250 -400);
FORCEPROP 1 LAST LOCATION C9L12
J 0
(3250 -350);
DISPLAY 0.617021 (3250 -350);
PAINT AQUA (3250 -350);
FORCEPROP 1 LASTPIN (3200 -400) $PN 1
J 0
(3210 -415);
DISPLAY 0.617021 (3210 -415);
PAINT ORANGE (3210 -415);
FORCEPROP 1 LASTPIN (3200 -600) $PN 2
J 0
(3210 -615);
DISPLAY 0.617021 (3210 -615);
PAINT ORANGE (3210 -615);
FORCEPROP 0 LAST GROUP PWR_BULK_CAP
J 0
(3265 -749);
DISPLAY 0.638298 (3265 -749);
PAINT BROWN (3265 -749);
DISPLAY BOTH (3265 -749);
FORCEPROP 2 LAST CDS_LIB mstr_discrete
J 0
(3200 -500);
PAINT ORANGE (3200 -500);
DISPLAY INVISIBLE (3200 -500);
FORCEPROP 0 LAST ROOM VDDQ_KLM_PWR_VR
J 0
(3250 -350);
DISPLAY 1.021277 (3250 -350);
PAINT ORANGE (3250 -350);
DISPLAY INVISIBLE (3250 -350);
FORCEPROP 1 LAST PATH I76
J 0
(3250 -350);
DISPLAY 1.319149 (3250 -350);
PAINT ORANGE (3250 -350);
DISPLAY INVISIBLE (3250 -350);
FORCEPROP 2 LAST CDS_LOCATION C9L12
J 0
(3250 -400);
DISPLAY 0.617021 (3250 -400);
PAINT AQUA (3250 -400);
DISPLAY INVISIBLE (3250 -400);
FORCEPROP 2 LAST SEC 1
J 0
(3250 -275);
DISPLAY 0.680851 (3250 -275);
PAINT MONO (3250 -275);
DISPLAY INVISIBLE (3250 -275);
FORCEPROP 2 LAST SEC_TYPE 3018
J 0
(3250 -275);
DISPLAY 1.021277 (3250 -275);
PAINT ORANGE (3250 -275);
DISPLAY INVISIBLE (3250 -275);
FORCEADD CAPP..1
(3500 -500);
FORCEPROP 1 LAST VOLTAGE 2.5V
J 0
(3550 -500);
DISPLAY 0.617021 (3550 -500);
PAINT SKYBLUE (3550 -500);
FORCEPROP 1 LAST TOLERANCE 20%
J 0
(3550 -450);
DISPLAY 0.617021 (3550 -450);
PAINT SKYBLUE (3550 -450);
FORCEPROP 1 LAST VALUE 470UF
J 0
(3550 -400);
DISPLAY 0.617021 (3550 -400);
PAINT SKYBLUE (3550 -400);
FORCEPROP 1 LAST MATERIAL ALUM
J 0
(3550 -550);
DISPLAY 0.617021 (3550 -550);
PAINT SKYBLUE (3550 -550);
FORCEPROP 1 LAST PACK_TYPE 3018
J 0
(3550 -600);
DISPLAY 0.617021 (3550 -600);
PAINT SKYBLUE (3550 -600);
FORCEPROP 1 LAST PART_NUMBER 699013-049
J 0
(3550 -650);
DISPLAY 0.617021 (3550 -650);
PAINT BLUE (3550 -650);
FORCEPROP 1 LAST LOCATION C9L4
J 0
(3550 -350);
DISPLAY 0.617021 (3550 -350);
PAINT AQUA (3550 -350);
FORCEPROP 1 LASTPIN (3500 -400) $PN 1
J 0
(3510 -415);
DISPLAY 0.617021 (3510 -415);
PAINT ORANGE (3510 -415);
FORCEPROP 1 LASTPIN (3500 -600) $PN 2
J 0
(3510 -615);
DISPLAY 0.617021 (3510 -615);
PAINT ORANGE (3510 -615);
FORCEPROP 0 LAST GROUP PWR_BULK_CAP
J 0
(3565 -699);
DISPLAY 0.638298 (3565 -699);
PAINT BROWN (3565 -699);
DISPLAY BOTH (3565 -699);
FORCEPROP 2 LAST CDS_LIB mstr_discrete
J 0
(3500 -500);
PAINT ORANGE (3500 -500);
DISPLAY INVISIBLE (3500 -500);
FORCEPROP 2 LAST CDS_LOCATION C9L4
J 0
(3550 -400);
DISPLAY 0.617021 (3550 -400);
PAINT AQUA (3550 -400);
DISPLAY INVISIBLE (3550 -400);
FORCEPROP 1 LAST PATH I77
J 0
(3550 -350);
DISPLAY 1.319149 (3550 -350);
PAINT ORANGE (3550 -350);
DISPLAY INVISIBLE (3550 -350);
FORCEPROP 0 LAST ROOM VDDQ_KLM_PWR_VR
J 0
(3550 -350);
DISPLAY 1.021277 (3550 -350);
PAINT ORANGE (3550 -350);
DISPLAY INVISIBLE (3550 -350);
FORCEPROP 2 LAST SEC_TYPE 3018
J 0
(3550 -275);
DISPLAY 1.021277 (3550 -275);
PAINT ORANGE (3550 -275);
DISPLAY INVISIBLE (3550 -275);
FORCEPROP 2 LAST SEC 1
J 0
(3550 -275);
DISPLAY 0.680851 (3550 -275);
PAINT MONO (3550 -275);
DISPLAY INVISIBLE (3550 -275);
FORCEADD CAPP..1
(3800 -500);
FORCEPROP 1 LAST VOLTAGE 2.5V
J 0
(3850 -500);
DISPLAY 0.617021 (3850 -500);
PAINT SKYBLUE (3850 -500);
FORCEPROP 1 LAST VALUE 470UF
J 0
(3850 -400);
DISPLAY 0.617021 (3850 -400);
PAINT SKYBLUE (3850 -400);
FORCEPROP 1 LAST TOLERANCE 20%
J 0
(3850 -450);
DISPLAY 0.617021 (3850 -450);
PAINT SKYBLUE (3850 -450);
FORCEPROP 1 LAST MATERIAL ALUM
J 0
(3850 -550);
DISPLAY 0.617021 (3850 -550);
PAINT SKYBLUE (3850 -550);
FORCEPROP 1 LAST PACK_TYPE 3018
J 0
(3850 -600);
DISPLAY 0.617021 (3850 -600);
PAINT SKYBLUE (3850 -600);
FORCEPROP 1 LAST PART_NUMBER 699013-049
J 0
(3850 -650);
DISPLAY 0.617021 (3850 -650);
PAINT BLUE (3850 -650);
FORCEPROP 1 LASTPIN (3800 -600) $PN 2
J 0
(3810 -615);
DISPLAY 0.617021 (3810 -615);
PAINT ORANGE (3810 -615);
FORCEPROP 1 LASTPIN (3800 -400) $PN 1
J 0
(3810 -415);
DISPLAY 0.617021 (3810 -415);
PAINT ORANGE (3810 -415);
FORCEPROP 1 LAST LOCATION C9L2
J 0
(3850 -350);
DISPLAY 0.617021 (3850 -350);
PAINT AQUA (3850 -350);
FORCEPROP 0 LAST GROUP PWR_BULK_CAP
J 0
(3865 -749);
DISPLAY 0.638298 (3865 -749);
PAINT BROWN (3865 -749);
DISPLAY BOTH (3865 -749);
FORCEPROP 2 LAST CDS_LIB mstr_discrete
J 0
(3800 -500);
PAINT ORANGE (3800 -500);
DISPLAY INVISIBLE (3800 -500);
FORCEPROP 2 LAST CDS_LOCATION C9L2
J 0
(3850 -400);
DISPLAY 0.617021 (3850 -400);
PAINT AQUA (3850 -400);
DISPLAY INVISIBLE (3850 -400);
FORCEPROP 1 LAST PATH I78
J 0
(3850 -350);
DISPLAY 1.319149 (3850 -350);
PAINT ORANGE (3850 -350);
DISPLAY INVISIBLE (3850 -350);
FORCEPROP 0 LAST ROOM VDDQ_KLM_PWR_VR
J 0
(3850 -350);
DISPLAY 1.021277 (3850 -350);
PAINT ORANGE (3850 -350);
DISPLAY INVISIBLE (3850 -350);
FORCEPROP 2 LAST SEC_TYPE 3018
J 0
(3850 -275);
DISPLAY 1.021277 (3850 -275);
PAINT ORANGE (3850 -275);
DISPLAY INVISIBLE (3850 -275);
FORCEPROP 2 LAST SEC 1
J 0
(3850 -275);
DISPLAY 0.680851 (3850 -275);
PAINT MONO (3850 -275);
DISPLAY INVISIBLE (3850 -275);
FORCEADD PVDDQ_KLM..1
(2900 -175);
FORCEPROP 3 LASTPIN (2900 -225) SIG_NAME PVDDQ_KLM\g
J 0
(2910 -215);
DISPLAY 0.659574 (2910 -215);
PAINT MONO (2910 -215);
DISPLAY INVISIBLE (2910 -215);
FORCEPROP 2 LAST ROOM VDDQ_KLM_PWR_VR
J 0
(3125 -75);
PAINT ORANGE (3125 -75);
DISPLAY INVISIBLE (3125 -75);
FORCEPROP 1 LAST PATH I80
J 0
(2950 -150);
DISPLAY 0.872340 (2950 -150);
PAINT AQUA (2950 -150);
DISPLAY INVISIBLE (2950 -150);
FORCEPROP 2 LAST CDS_LIB mstr_symbols
J 0
(2900 -175);
PAINT ORANGE (2900 -175);
DISPLAY INVISIBLE (2900 -175);
FORCEPROP 2 LAST BOM_COST MEM_VRD_PVPP_AB
J 0
(2950 -75);
PAINT MONO (2950 -75);
DISPLAY INVISIBLE (2950 -75);
FORCEPROP 1 LAST VOLTAGE 1.2V
J 0
(2855 -218);
DISPLAY 0.340426 (2855 -218);
PAINT SKYBLUE (2855 -218);
DISPLAY INVISIBLE (2855 -218);
FORCEPROP 1 LAST BODY_TYPE PLUMBING
J 0
(2855 -218);
DISPLAY 0.340426 (2855 -218);
PAINT GREEN (2855 -218);
DISPLAY INVISIBLE (2855 -218);
FORCEPROP 1 LAST HDL_POWER PVDDQ_KLM
J 1
(2900 -125);
DISPLAY 0.872340 (2900 -125);
PAINT GREEN (2900 -125);
DISPLAY INVISIBLE (2900 -125);
FORCEADD GND..1
(2900 -825);
FORCEPROP 3 LASTPIN (2900 -775) SIG_NAME GND\g
J 0
(2910 -765);
DISPLAY 0.659574 (2910 -765);
PAINT MONO (2910 -765);
DISPLAY INVISIBLE (2910 -765);
FORCEPROP 1 LAST PATH I81
J 0
(2975 -825);
DISPLAY 1.170213 (2975 -825);
PAINT AQUA (2975 -825);
DISPLAY INVISIBLE (2975 -825);
FORCEPROP 2 LAST CDS_LIB mstr_symbols
J 0
(2900 -825);
PAINT ORANGE (2900 -825);
DISPLAY INVISIBLE (2900 -825);
FORCEPROP 1 LAST SIZE 1B
J 0
(2975 -875);
DISPLAY 0.893617 (2975 -875);
PAINT GREEN (2975 -875);
DISPLAY INVISIBLE (2975 -875);
FORCEPROP 1 LAST VOLTAGE 0
J 0
(2900 -825);
PAINT SKYBLUE (2900 -825);
DISPLAY INVISIBLE (2900 -825);
FORCEPROP 2 LAST BOM_COST MEM_VRD_PVPP_AB
J 0
(2575 -750);
PAINT MONO (2575 -750);
DISPLAY INVISIBLE (2575 -750);
FORCEPROP 1 LAST BODY_TYPE PLUMBING
J 0
(2855 -868);
DISPLAY 0.340426 (2855 -868);
PAINT GREEN (2855 -868);
DISPLAY INVISIBLE (2855 -868);
FORCEPROP 1 LAST HDL_POWER GND
J 0
(2900 -675);
DISPLAY 0.893617 (2900 -675);
PAINT GREEN (2900 -675);
DISPLAY INVISIBLE (2900 -675);
FORCEADD PVDDQ_KLM..1
(2400 3100);
FORCEPROP 3 LASTPIN (2400 3050) SIG_NAME PVDDQ_KLM\g
J 0
(2410 3060);
DISPLAY 0.659574 (2410 3060);
PAINT MONO (2410 3060);
DISPLAY INVISIBLE (2410 3060);
FORCEPROP 2 LAST ROOM VDDQ_KLM_PWR_VR
J 0
(2650 3200);
PAINT ORANGE (2650 3200);
DISPLAY INVISIBLE (2650 3200);
FORCEPROP 1 LAST PATH I93
J 0
(2450 3125);
DISPLAY 0.872340 (2450 3125);
PAINT AQUA (2450 3125);
DISPLAY INVISIBLE (2450 3125);
FORCEPROP 2 LAST CDS_LIB mstr_symbols
J 0
(2400 3100);
PAINT ORANGE (2400 3100);
DISPLAY INVISIBLE (2400 3100);
FORCEPROP 2 LAST BOM_COST MEM_VRD_PVDDQ_CD
J 0
(2475 3200);
PAINT MONO (2475 3200);
DISPLAY INVISIBLE (2475 3200);
FORCEPROP 1 LAST VOLTAGE 1.2V
J 0
(2355 3057);
DISPLAY 0.340426 (2355 3057);
PAINT SKYBLUE (2355 3057);
DISPLAY INVISIBLE (2355 3057);
FORCEPROP 1 LAST BODY_TYPE PLUMBING
J 0
(2355 3057);
DISPLAY 0.340426 (2355 3057);
PAINT GREEN (2355 3057);
DISPLAY INVISIBLE (2355 3057);
FORCEPROP 1 LAST HDL_POWER PVDDQ_KLM
J 1
(2400 3150);
DISPLAY 0.872340 (2400 3150);
PAINT GREEN (2400 3150);
DISPLAY INVISIBLE (2400 3150);
FORCEADD GND..1
(2400 2400);
FORCEPROP 3 LASTPIN (2400 2450) SIG_NAME GND\g
J 0
(2410 2460);
DISPLAY 0.659574 (2410 2460);
PAINT MONO (2410 2460);
DISPLAY INVISIBLE (2410 2460);
FORCEPROP 1 LAST PATH I94
J 0
(2475 2400);
DISPLAY 1.170213 (2475 2400);
PAINT AQUA (2475 2400);
DISPLAY INVISIBLE (2475 2400);
FORCEPROP 2 LAST CDS_LIB mstr_symbols
J 0
(2400 2400);
PAINT ORANGE (2400 2400);
DISPLAY INVISIBLE (2400 2400);
FORCEPROP 1 LAST SIZE 1B
J 0
(2475 2350);
DISPLAY 0.893617 (2475 2350);
PAINT GREEN (2475 2350);
DISPLAY INVISIBLE (2475 2350);
FORCEPROP 1 LAST VOLTAGE 0
J 0
(2400 2400);
PAINT SKYBLUE (2400 2400);
DISPLAY INVISIBLE (2400 2400);
FORCEPROP 2 LAST BOM_COST MEM_VRD_PVDDQ_CD
J 0
(2075 2475);
PAINT MONO (2075 2475);
DISPLAY INVISIBLE (2075 2475);
FORCEPROP 2 LAST ROOM VDDQ_KLM_PWR_VR
J 0
(1850 2475);
PAINT ORANGE (1850 2475);
DISPLAY INVISIBLE (1850 2475);
FORCEPROP 1 LAST BODY_TYPE PLUMBING
J 0
(2355 2357);
DISPLAY 0.340426 (2355 2357);
PAINT GREEN (2355 2357);
DISPLAY INVISIBLE (2355 2357);
FORCEPROP 1 LAST HDL_POWER GND
J 0
(2400 2550);
DISPLAY 0.893617 (2400 2550);
PAINT GREEN (2400 2550);
DISPLAY INVISIBLE (2400 2550);
FORCEADD DNS..2
(-370 1920);
PAINT RED (-370 1920);
FORCEPROP 2 LAST CDS_LIB mstr_misc
J 0
(-370 1920);
PAINT ORANGE (-370 1920);
DISPLAY INVISIBLE (-370 1920);
FORCEPROP 1 LAST COMMENT_BODY TRUE
R 1
J 0
(-295 1695);
DISPLAY 0.872340 (-295 1695);
PAINT GREEN (-295 1695);
DISPLAY INVISIBLE (-295 1695);
FORCEADD DNS..3
(80 1720);
PAINT RED (80 1720);
FORCEPROP 2 LAST CDS_LIB mstr_misc
J 0
(80 1720);
PAINT ORANGE (80 1720);
DISPLAY INVISIBLE (80 1720);
FORCEPROP 1 LAST COMMENT_BODY TRUE
R 1
J 0
(155 1495);
DISPLAY 0.872340 (155 1495);
PAINT GREEN (155 1495);
DISPLAY INVISIBLE (155 1495);
FORCEADD DNS..3
(80 2170);
PAINT RED (80 2170);
FORCEPROP 2 LAST CDS_LIB mstr_misc
J 0
(80 2170);
PAINT ORANGE (80 2170);
DISPLAY INVISIBLE (80 2170);
FORCEPROP 1 LAST COMMENT_BODY TRUE
R 1
J 0
(155 1945);
DISPLAY 0.872340 (155 1945);
PAINT GREEN (155 1945);
DISPLAY INVISIBLE (155 1945);
FORCEADD INTEL_CORP_BPAGE..1
(5475 -1550);
FORCEPROP 1 LAST CDS_CON_LAST_MODIFIED Fri Jun 16 17:49:22 2017
J 0
(4050 -1225);
PAINT GREEN (4050 -1225);
DISPLAY INVISIBLE (4050 -1225);
FORCEPROP 1 LAST CUSTOM_TXT_CDS <CURRENT_DESIGN_SHEET> OF <TOTAL_DESIGN_SHEETS>
J 0
(4975 -1525);
PAINT ORANGE (4975 -1525);
FORCEPROP 2 LAST CUSTOM_TXT_CDS <XR_PAGE_TITLE>
J 0
(-2415 3700);
DISPLAY 0.638298 (-2415 3700);
PAINT PINK (-2415 3700);
DISPLAY INVISIBLE (-2415 3700);
FORCEPROP 2 LAST CUSTOM_TXT_CDS <CON_LAST_MODIFIED>
J 0
(1475 -1450);
PAINT ORANGE (1475 -1450);
FORCEPROP 2 LAST CUSTOM_TXT_CDS <CON_PAGE_NUM> OF <CON_TOTAL_PAGES>
J 0
(4975 -1525);
PAINT GREEN (4975 -1525);
FORCEPROP 1 LAST SCH_TITLE VDDQ KLM DECAP (3 OF 3)
J 0
(-2475 -1500);
DISPLAY 1.212766 (-2475 -1500);
PAINT GREEN (-2475 -1500);
FORCEPROP 2 LAST CDS_LIB mstr_symbols
J 0
(5475 -1550);
PAINT ORANGE (5475 -1550);
DISPLAY INVISIBLE (5475 -1550);
FORCEPROP 2 LAST PAGE_BORDER TRUE
J 0
(-2415 3700);
DISPLAY 0.851064 (-2415 3700);
PAINT PINK (-2415 3700);
DISPLAY INVISIBLE (-2415 3700);
FORCEPROP 2 LAST ROOM VDDQ_KLM_PWR_VR
J 0
(-2625 3550);
PAINT ORANGE (-2625 3550);
DISPLAY INVISIBLE (-2625 3550);
FORCEPROP 1 LAST COMMENT_BODY TRUE
J 0
(5487 -1538);
DISPLAY 0.446809 (5487 -1538);
PAINT GREEN (5487 -1538);
DISPLAY INVISIBLE (5487 -1538);
FORCEPROP 2 LAST CDS_XR_PAGE_TITLE CR-228 : @BASEBOARD_FAB2_LIB.BASEBOARD_FAB2(SCH_1):PAGE228
J 0
(-2415 3700);
DISPLAY 0.638298 (-2415 3700);
PAINT PINK (-2415 3700);
DISPLAY INVISIBLE (-2415 3700);
WIRE 16 -1 (2525 1600)(2525 1650);
WIRE 16 -1 (2525 1600)(2875 1600);
WIRE 16 -1 (2525 1600)(2525 1525);
WIRE 16 -1 (3275 1600)(2875 1600);
WIRE 16 -1 (2875 1525)(2875 1600);
WIRE 16 -1 (3625 1600)(3275 1600);
WIRE 16 -1 (3275 1525)(3275 1600);
WIRE 16 -1 (3975 1600)(3625 1600);
WIRE 16 -1 (3625 1525)(3625 1600);
WIRE 16 -1 (4375 1600)(3975 1600);
WIRE 16 -1 (3975 1525)(3975 1600);
WIRE 16 -1 (4375 1525)(4375 1600);
WIRE 16 -1 (4250 1100)(4250 1175);
WIRE 16 -1 (4250 1175)(3975 1175);
WIRE 16 -1 (4250 1175)(4375 1175);
WIRE 16 -1 (4375 1325)(4375 1175);
WIRE 16 -1 (3625 1175)(3975 1175);
WIRE 16 -1 (3975 1325)(3975 1175);
WIRE 16 -1 (3275 1175)(3625 1175);
WIRE 16 -1 (3625 1325)(3625 1175);
WIRE 16 -1 (2875 1175)(3275 1175);
WIRE 16 -1 (3275 1325)(3275 1175);
WIRE 16 -1 (2525 1175)(2875 1175);
WIRE 16 -1 (2875 1325)(2875 1175);
WIRE 16 -1 (2525 1325)(2525 1175);
WIRE 16 -1 (-675 1100)(-675 1300);
WIRE 16 -1 (-900 1100)(-675 1100);
WIRE 16 -1 (-675 1000)(-675 1100);
WIRE 16 -1 (-675 800)(-675 725);
WIRE 16 -1 (-1400 1325)(-1400 1100);
WIRE 16 -1 (-1400 1100)(-1200 1100);
WIRE 16 -1 (-250 2675)(-250 2725);
WIRE 16 -1 (-600 2725)(-250 2725);
WIRE 16 -1 (-250 2875)(-250 2725);
WIRE 16 -1 (-950 2725)(-600 2725);
WIRE 16 -1 (-600 2875)(-600 2725);
WIRE 16 -1 (-1300 2725)(-950 2725);
WIRE 16 -1 (-950 2875)(-950 2725);
WIRE 16 -1 (-1300 2875)(-1300 2725);
WIRE 16 -1 (-2325 3150)(-2325 3200);
WIRE 16 -1 (-2325 3150)(-1925 3150);
WIRE 16 -1 (-2325 3150)(-2325 3075);
WIRE 16 -1 (-1925 3075)(-1925 3150);
WIRE 16 -1 (2550 900)(2550 950);
WIRE 16 -1 (2550 900)(2900 900);
WIRE 16 -1 (2550 900)(2550 825);
WIRE 16 -1 (3300 900)(2900 900);
WIRE 16 -1 (2900 825)(2900 900);
WIRE 16 -1 (3300 825)(3300 900);
WIRE 16 -1 (3300 375)(3300 475);
WIRE 16 -1 (2900 475)(3300 475);
WIRE 16 -1 (3300 625)(3300 475);
WIRE 16 -1 (2550 475)(2900 475);
WIRE 16 -1 (2900 625)(2900 475);
WIRE 16 -1 (2550 625)(2550 475);
WIRE 16 -1 (-1300 3150)(-1300 3200);
WIRE 16 -1 (-950 3150)(-1300 3150);
WIRE 16 -1 (-1300 3075)(-1300 3150);
WIRE 16 -1 (-600 3150)(-950 3150);
WIRE 16 -1 (-950 3075)(-950 3150);
WIRE 16 -1 (-250 3150)(-600 3150);
WIRE 16 -1 (-600 3075)(-600 3150);
WIRE 16 -1 (-250 3075)(-250 3150);
WIRE 16 -1 (-2325 2525)(-2325 2550);
WIRE 16 -1 (-1925 2550)(-2325 2550);
WIRE 16 -1 (-2325 2875)(-2325 2550);
WIRE 16 -1 (-1925 2875)(-1925 2550);
WIRE 16 -1 (-2250 75)(-2250 125);
WIRE 16 -1 (-2250 75)(-1950 75);
WIRE 16 -1 (-2250 25)(-2250 75);
WIRE 16 -1 (-1950 75)(-1650 75);
WIRE 16 -1 (-1950 25)(-1950 75);
WIRE 16 -1 (-1650 75)(-1375 75);
WIRE 16 -1 (-1650 25)(-1650 75);
WIRE 16 -1 (-1100 75)(-1375 75);
WIRE 16 -1 (-1375 25)(-1375 75);
WIRE 16 -1 (-800 75)(-1100 75);
WIRE 16 -1 (-1100 25)(-1100 75);
WIRE 16 -1 (-500 75)(-800 75);
WIRE 16 -1 (-800 25)(-800 75);
WIRE 16 -1 (-225 75)(-500 75);
WIRE 16 -1 (-500 25)(-500 75);
WIRE 16 -1 (100 75)(-225 75);
WIRE 16 -1 (-225 25)(-225 75);
WIRE 16 -1 (400 75)(100 75);
WIRE 16 -1 (100 25)(100 75);
WIRE 16 -1 (700 75)(400 75);
WIRE 16 -1 (400 25)(400 75);
WIRE 16 -1 (975 75)(700 75);
WIRE 16 -1 (700 25)(700 75);
WIRE 16 -1 (1250 75)(975 75);
WIRE 16 -1 (975 25)(975 75);
WIRE 16 -1 (1550 75)(1250 75);
WIRE 16 -1 (1250 25)(1250 75);
WIRE 16 -1 (1850 75)(1550 75);
WIRE 16 -1 (1550 25)(1550 75);
WIRE 16 -1 (2125 75)(1850 75);
WIRE 16 -1 (1850 25)(1850 75);
WIRE 16 -1 (2125 25)(2125 75);
WIRE 16 -1 (-2250 -300)(-2250 -350);
WIRE 16 -1 (-1950 -300)(-2250 -300);
WIRE 16 -1 (-2250 -175)(-2250 -300);
WIRE 16 -1 (-1650 -300)(-1950 -300);
WIRE 16 -1 (-1950 -175)(-1950 -300);
WIRE 16 -1 (-1650 -300)(-1375 -300);
WIRE 16 -1 (-1650 -175)(-1650 -300);
WIRE 16 -1 (-1100 -300)(-1375 -300);
WIRE 16 -1 (-1375 -175)(-1375 -300);
WIRE 16 -1 (-800 -300)(-1100 -300);
WIRE 16 -1 (-1100 -175)(-1100 -300);
WIRE 16 -1 (-500 -300)(-800 -300);
WIRE 16 -1 (-800 -175)(-800 -300);
WIRE 16 -1 (-225 -300)(-500 -300);
WIRE 16 -1 (-500 -175)(-500 -300);
WIRE 16 -1 (100 -300)(-225 -300);
WIRE 16 -1 (-225 -175)(-225 -300);
WIRE 16 -1 (400 -300)(100 -300);
WIRE 16 -1 (100 -175)(100 -300);
WIRE 16 -1 (700 -300)(400 -300);
WIRE 16 -1 (400 -175)(400 -300);
WIRE 16 -1 (975 -300)(700 -300);
WIRE 16 -1 (700 -175)(700 -300);
WIRE 16 -1 (1250 -300)(975 -300);
WIRE 16 -1 (975 -175)(975 -300);
WIRE 16 -1 (1550 -300)(1250 -300);
WIRE 16 -1 (1250 -175)(1250 -300);
WIRE 16 -1 (1850 -300)(1550 -300);
WIRE 16 -1 (1550 -175)(1550 -300);
WIRE 16 -1 (2125 -300)(1850 -300);
WIRE 16 -1 (1850 -175)(1850 -300);
WIRE 16 -1 (2125 -175)(2125 -300);
WIRE 16 -1 (-2225 -625)(-2225 -575);
WIRE 16 -1 (-2225 -625)(-1925 -625);
WIRE 16 -1 (-2225 -675)(-2225 -625);
WIRE 16 -1 (-1925 -625)(-1625 -625);
WIRE 16 -1 (-1925 -675)(-1925 -625);
WIRE 16 -1 (-1625 -625)(-1350 -625);
WIRE 16 -1 (-1625 -675)(-1625 -625);
WIRE 16 -1 (-1075 -625)(-1350 -625);
WIRE 16 -1 (-1350 -675)(-1350 -625);
WIRE 16 -1 (-775 -625)(-1075 -625);
WIRE 16 -1 (-1075 -675)(-1075 -625);
WIRE 16 -1 (-475 -625)(-775 -625);
WIRE 16 -1 (-775 -675)(-775 -625);
WIRE 16 -1 (-200 -625)(-475 -625);
WIRE 16 -1 (-475 -675)(-475 -625);
WIRE 16 -1 (125 -625)(-200 -625);
WIRE 16 -1 (-200 -675)(-200 -625);
WIRE 16 -1 (425 -625)(125 -625);
WIRE 16 -1 (125 -675)(125 -625);
WIRE 16 -1 (725 -625)(425 -625);
WIRE 16 -1 (425 -675)(425 -625);
WIRE 16 -1 (1000 -625)(725 -625);
WIRE 16 -1 (725 -675)(725 -625);
WIRE 16 -1 (1275 -625)(1000 -625);
WIRE 16 -1 (1000 -675)(1000 -625);
WIRE 16 -1 (1575 -625)(1275 -625);
WIRE 16 -1 (1275 -675)(1275 -625);
WIRE 16 -1 (1875 -625)(1575 -625);
WIRE 16 -1 (1575 -675)(1575 -625);
WIRE 16 -1 (2150 -625)(1875 -625);
WIRE 16 -1 (1875 -675)(1875 -625);
WIRE 16 -1 (2150 -675)(2150 -625);
WIRE 16 -1 (-2225 -1000)(-2225 -1025);
WIRE 16 -1 (-1925 -1000)(-2225 -1000);
WIRE 16 -1 (-2225 -875)(-2225 -1000);
WIRE 16 -1 (-1625 -1000)(-1925 -1000);
WIRE 16 -1 (-1925 -875)(-1925 -1000);
WIRE 16 -1 (-1625 -1000)(-1350 -1000);
WIRE 16 -1 (-1625 -875)(-1625 -1000);
WIRE 16 -1 (-1075 -1000)(-1350 -1000);
WIRE 16 -1 (-1350 -875)(-1350 -1000);
WIRE 16 -1 (-775 -1000)(-1075 -1000);
WIRE 16 -1 (-1075 -875)(-1075 -1000);
WIRE 16 -1 (-475 -1000)(-775 -1000);
WIRE 16 -1 (-775 -875)(-775 -1000);
WIRE 16 -1 (-200 -1000)(-475 -1000);
WIRE 16 -1 (-475 -875)(-475 -1000);
WIRE 16 -1 (125 -1000)(-200 -1000);
WIRE 16 -1 (-200 -875)(-200 -1000);
WIRE 16 -1 (425 -1000)(125 -1000);
WIRE 16 -1 (125 -875)(125 -1000);
WIRE 16 -1 (725 -1000)(425 -1000);
WIRE 16 -1 (425 -875)(425 -1000);
WIRE 16 -1 (1000 -1000)(725 -1000);
WIRE 16 -1 (725 -875)(725 -1000);
WIRE 16 -1 (1275 -1000)(1000 -1000);
WIRE 16 -1 (1000 -875)(1000 -1000);
WIRE 16 -1 (1575 -1000)(1275 -1000);
WIRE 16 -1 (1275 -875)(1275 -1000);
WIRE 16 -1 (1875 -1000)(1575 -1000);
WIRE 16 -1 (1575 -875)(1575 -1000);
WIRE 16 -1 (2150 -1000)(1875 -1000);
WIRE 16 -1 (1875 -875)(1875 -1000);
WIRE 16 -1 (2150 -875)(2150 -1000);
WIRE 16 -1 (650 2975)(650 3050);
WIRE 16 -1 (1125 2975)(650 2975);
WIRE 16 -1 (650 2875)(650 2975);
WIRE 16 -1 (1125 2975)(1625 2975);
WIRE 16 -1 (1125 2875)(1125 2975);
WIRE 16 -1 (1625 2875)(1625 2975);
WIRE 16 -1 (650 2375)(650 2400);
WIRE 16 -1 (1125 2400)(650 2400);
WIRE 16 -1 (650 2675)(650 2400);
WIRE 16 -1 (1125 2400)(1625 2400);
WIRE 16 -1 (1125 2675)(1125 2400);
WIRE 16 -1 (1625 2400)(1625 2675);
WIRE 16 -1 (1650 1550)(1650 1500);
WIRE 16 -1 (1300 1550)(1650 1550);
WIRE 16 -1 (1650 1550)(1650 1700);
WIRE 16 -1 (950 1550)(1300 1550);
WIRE 16 -1 (1300 1700)(1300 1550);
WIRE 16 -1 (600 1550)(950 1550);
WIRE 16 -1 (950 1700)(950 1550);
WIRE 16 -1 (600 1700)(600 1550);
WIRE 16 -1 (600 1950)(600 2000);
WIRE 16 -1 (600 1950)(950 1950);
WIRE 16 -1 (600 1900)(600 1950);
WIRE 16 -1 (950 1950)(1300 1950);
WIRE 16 -1 (950 1950)(950 1900);
WIRE 16 -1 (1300 1950)(1650 1950);
WIRE 16 -1 (1300 1950)(1300 1900);
WIRE 16 -1 (1650 1950)(1650 1900);
WIRE 16 -1 (525 550)(525 625);
WIRE 16 -1 (525 825)(525 900);
WIRE 16 -1 (275 1550)(275 1725);
WIRE 16 -1 (275 1725)(225 1725);
WIRE 16 -1 (300 2325)(300 2175);
WIRE 16 -1 (300 2175)(225 2175);
WIRE 16 -1 (2900 -300)(2900 -225);
WIRE 16 -1 (2900 -300)(3200 -300);
WIRE 16 -1 (2900 -400)(2900 -300);
WIRE 16 -1 (3500 -300)(3200 -300);
WIRE 16 -1 (3200 -400)(3200 -300);
WIRE 16 -1 (3800 -300)(3500 -300);
WIRE 16 -1 (3500 -400)(3500 -300);
WIRE 16 -1 (4100 -300)(3800 -300);
WIRE 16 -1 (3800 -400)(3800 -300);
WIRE 16 -1 (4100 -400)(4100 -300);
WIRE 16 -1 (2900 -750)(2900 -775);
WIRE 16 -1 (3200 -750)(2900 -750);
WIRE 16 -1 (2900 -600)(2900 -750);
WIRE 16 -1 (3500 -750)(3200 -750);
WIRE 16 -1 (3200 -600)(3200 -750);
WIRE 16 -1 (3800 -750)(3500 -750);
WIRE 16 -1 (3500 -600)(3500 -750);
WIRE 16 -1 (4100 -750)(3800 -750);
WIRE 16 -1 (3800 -600)(3800 -750);
WIRE 16 -1 (4100 -600)(4100 -750);
WIRE 16 -1 (2400 3000)(2400 3050);
WIRE 16 -1 (2400 3000)(2750 3000);
WIRE 16 -1 (2400 3000)(2400 2925);
WIRE 16 -1 (3150 3000)(2750 3000);
WIRE 16 -1 (2750 2925)(2750 3000);
WIRE 16 -1 (3500 3000)(3150 3000);
WIRE 16 -1 (3150 2925)(3150 3000);
WIRE 16 -1 (3850 3000)(3500 3000);
WIRE 16 -1 (3500 2925)(3500 3000);
WIRE 16 -1 (4250 3000)(3850 3000);
WIRE 16 -1 (3850 2925)(3850 3000);
WIRE 16 -1 (4600 3000)(4250 3000);
WIRE 16 -1 (4250 2925)(4250 3000);
WIRE 16 -1 (4950 3000)(4600 3000);
WIRE 16 -1 (4600 2925)(4600 3000);
WIRE 16 -1 (4950 2925)(4950 3000);
WIRE 16 -1 (2400 2450)(2400 2500);
WIRE 16 -1 (2400 2500)(2750 2500);
WIRE 16 -1 (2400 2725)(2400 2500);
WIRE 16 -1 (2750 2500)(3150 2500);
WIRE 16 -1 (2750 2725)(2750 2500);
WIRE 16 -1 (3150 2500)(3500 2500);
WIRE 16 -1 (3150 2725)(3150 2500);
WIRE 16 -1 (3500 2500)(3850 2500);
WIRE 16 -1 (3500 2725)(3500 2500);
WIRE 16 -1 (4250 2500)(3850 2500);
WIRE 16 -1 (3850 2725)(3850 2500);
WIRE 16 -1 (4250 2500)(4600 2500);
WIRE 16 -1 (4250 2725)(4250 2500);
WIRE 16 -1 (4600 2500)(4950 2500);
WIRE 16 -1 (4600 2725)(4600 2500);
WIRE 16 -1 (4950 2725)(4950 2500);
WIRE 16 2175 (2300 2150)(5375 2150);
WIRE 3 682 (2250 3200)(2250 200);
WIRE 3 682 (5350 3200)(2250 3200);
WIRE 3 682 (2250 200)(5350 200);
WIRE 3 682 (5350 200)(5350 3200);
WIRE 3 682 (-1500 3350)(-1500 2600);
WIRE 3 682 (50 3350)(-1500 3350);
WIRE 3 682 (-1500 2600)(50 2600);
WIRE 3 682 (50 2600)(50 3350);
WIRE 3 682 (-2400 2450)(-2400 3125);
WIRE 3 682 (-1675 2450)(-2400 2450);
WIRE 3 682 (-2400 3125)(-1675 3125);
WIRE 3 682 (-1675 3125)(-1675 2450);
WIRE 16 682 (-2475 2400)(-2475 3375);
WIRE 16 682 (150 2400)(-2475 2400);
WIRE 16 682 (150 3375)(-2475 3375);
WIRE 16 682 (150 3375)(150 2400);
WIRE 16 682 (5225 -75)(2700 -75);
WIRE 16 682 (5225 -1050)(5225 -75);
WIRE 16 682 (2700 -75)(2700 -1050);
WIRE 16 682 (2700 -1050)(5225 -1050);
WIRE 16 2175 (2225 125)(2225 3325);
WIRE 16 2175 (5425 125)(2225 125);
WIRE 16 2175 (2225 3325)(5425 3325);
WIRE 16 2175 (5425 3325)(5425 125);
WIRE 3 682 (400 1400)(2000 1400);
WIRE 3 682 (400 2150)(400 1400);
WIRE 3 682 (2000 1400)(2000 2150);
WIRE 3 682 (2000 2150)(400 2150);
WIRE 3 682 (3550 850)(3850 850);
WIRE 3 682 (3550 1050)(3550 850);
WIRE 3 682 (150 1075)(150 450);
WIRE 3 682 (1100 1075)(150 1075);
WIRE 3 682 (150 450)(1100 450);
WIRE 3 682 (1100 450)(1100 1075);
WIRE 3 682 (500 2300)(500 3200);
WIRE 3 682 (2175 2300)(500 2300);
WIRE 3 682 (500 3200)(2175 3200);
WIRE 3 682 (2175 3200)(2175 2300);
WIRE 16 -1 (-875 2150)(-1600 2150);
FORCEPROP 2 LAST SIG_NAME VSENSE_PVDDQ_KLM_P
J 0
(-1605 2165);
DISPLAY 0.617021 (-1605 2165);
PAINT ORANGE (-1605 2165);
WIRE 16 -1 (-875 2025)(-875 2150);
WIRE 16 -1 (-475 2025)(-875 2025);
WIRE 16 -1 (-475 2175)(-475 2025);
WIRE 16 -1 (-375 2175)(-475 2175);
WIRE 16 -1 (-75 2175)(-375 2175);
WIRE 16 -1 (-375 2025)(-375 2175);
WIRE 16 -1 (-375 1825)(-375 1725);
WIRE 16 -1 (-75 1725)(-375 1725);
WIRE 16 -1 (-375 1725)(-475 1725);
WIRE 16 -1 (-475 1950)(-475 1725);
WIRE 16 -1 (-875 1950)(-475 1950);
WIRE 16 -1 (-875 1800)(-875 1950);
WIRE 16 -1 (-1575 1800)(-875 1800);
FORCEPROP 2 LAST SIG_NAME VSENSE_PVDDQ_KLM_N
J 0
(-1585 1810);
DISPLAY 0.617021 (-1585 1810);
PAINT ORANGE (-1585 1810);
WIRE 3 682 (-2450 275)(-2450 -1125);
WIRE 3 682 (2650 275)(-2450 275);
WIRE 3 682 (-2450 -1125)(2650 -1125);
WIRE 3 682 (2650 -1125)(2650 275);
DOT 1 (2750 3000);
DOT 1 (2400 2500);
DOT 1 (2750 2500);
DOT 1 (2400 3000);
DOT 1 (3975 1175);
DOT 1 (2525 1600);
DOT 1 (-1625 -625);
DOT 1 (-475 -1000);
DOT 1 (3500 3000);
DOT 1 (425 -625);
DOT 1 (725 -625);
DOT 1 (-1075 -1000);
DOT 1 (-800 -300);
DOT 1 (-1650 -300);
DOT 1 (-2225 -625);
DOT 1 (1550 -300);
DOT 1 (700 -300);
DOT 1 (-200 -625);
DOT 1 (400 -300);
DOT 1 (-225 -300);
DOT 1 (-500 -300);
DOT 1 (-1925 -625);
DOT 1 (975 -300);
DOT 1 (4600 3000);
DOT 1 (4250 1175);
DOT 1 (3150 3000);
DOT 1 (3975 1600);
DOT 1 (3625 1600);
DOT 1 (3625 1175);
DOT 1 (3275 1600);
DOT 1 (3300 475);
DOT 1 (2875 1175);
DOT 1 (2900 900);
DOT 1 (2550 900);
DOT 1 (1650 1550);
DOT 1 (1300 1950);
DOT 1 (1300 1550);
DOT 1 (1850 75);
DOT 1 (1550 75);
DOT 1 (1250 75);
DOT 1 (950 1950);
DOT 1 (950 1550);
DOT 1 (975 75);
DOT 1 (700 75);
DOT 1 (400 75);
DOT 1 (100 75);
DOT 1 (1850 -300);
DOT 1 (1875 -625);
DOT 1 (1875 -1000);
DOT 1 (1575 -625);
DOT 1 (1575 -1000);
DOT 1 (1250 -300);
DOT 1 (1275 -625);
DOT 1 (1275 -1000);
DOT 1 (1000 -625);
DOT 1 (1000 -1000);
DOT 1 (725 -1000);
DOT 1 (100 -300);
DOT 1 (425 -1000);
DOT 1 (125 -625);
DOT 1 (125 -1000);
DOT 1 (-600 3150);
DOT 1 (-950 3150);
DOT 1 (-250 2725);
DOT 1 (-375 2175);
DOT 1 (-600 2725);
DOT 1 (-950 2725);
DOT 1 (-1300 3150);
DOT 1 (-375 1725);
DOT 1 (-675 1100);
DOT 1 (-225 75);
DOT 1 (-500 75);
DOT 1 (-800 75);
DOT 1 (-1100 75);
DOT 1 (-1375 75);
DOT 1 (-1650 75);
DOT 1 (-1950 75);
DOT 1 (-2325 3150);
DOT 1 (-2250 75);
DOT 1 (-200 -1000);
DOT 1 (-775 -625);
DOT 1 (-775 -1000);
DOT 1 (-1100 -300);
DOT 1 (-1375 -300);
DOT 1 (-1350 -625);
DOT 1 (-1350 -1000);
DOT 1 (-1625 -1000);
DOT 1 (-1925 -1000);
DOT 1 (-2250 -300);
DOT 1 (-2225 -1000);
DOT 1 (-475 -625);
DOT 1 (4600 2500);
DOT 1 (3150 2500);
DOT 1 (-2325 2550);
DOT 1 (1125 2975);
DOT 1 (650 2975);
DOT 1 (650 2400);
DOT 1 (1125 2400);
DOT 1 (2900 475);
DOT 1 (4250 2500);
DOT 1 (3500 2500);
DOT 1 (2900 -300);
DOT 1 (3200 -300);
DOT 1 (3800 -300);
DOT 1 (3500 -300);
DOT 1 (2900 -750);
DOT 1 (3200 -750);
DOT 1 (3500 -750);
DOT 1 (3800 -750);
DOT 1 (4250 3000);
DOT 1 (-1075 -625);
DOT 1 (-1950 -300);
DOT 1 (2875 1600);
DOT 1 (600 1950);
DOT 1 (3275 1175);
DOT 1 (3850 3000);
DOT 1 (3850 2500);
FORCENOTE
BOTTOM SIDE: 805
(-2254 3192) 0;
DISPLAY LEFT (-2254 3192);
DISPLAY 0.638298 (-2254 3192);
PAINT PURPLE (-2254 3192);
FORCENOTE
TP FAB3-DVT NOPOP FROM SS BOM 20161220
(-2400 2350) 0;
DISPLAY LEFT (-2400 2350);
DISPLAY 0.638298 (-2400 2350);
PAINT RED (-2400 2350);
FORCENOTE
INPUT FILTER
(-1405 780) 0;
DISPLAY LEFT (-1405 780);
PAINT PURPLE (-1405 780);
FORCENOTE
TP FAB1 CHANGE L1B1 PN 0122
(-1525 600) 0;
DISPLAY LEFT (-1525 600);
DISPLAY 1.021277 (-1525 600);
PAINT RED (-1525 600);
FORCENOTE
PLACE NEAR VR OUTPUT INDUCTORS
(3125 -975) 0;
DISPLAY LEFT (3125 -975);
DISPLAY 1.021277 (3125 -975);
PAINT PURPLE (3125 -975);
FORCENOTE
TP FAB3-DVT CHANGE CAP IN SS BOM 20161220
(3850 850) 0;
DISPLAY LEFT (3850 850);
DISPLAY 0.638298 (3850 850);
PAINT RED (3850 850);
FORCENOTE
TP FAB1 CHANGE CAP 0322
(-1500 2550) 0;
DISPLAY LEFT (-1500 2550);
DISPLAY 1.021277 (-1500 2550);
PAINT RED (-1500 2550);
FORCENOTE
TP FAB1 CHANGE CONNECTION 0318
(50 400) 0;
DISPLAY LEFT (50 400);
DISPLAY 0.638298 (50 400);
PAINT RED (50 400);
FORCENOTE
TP FAB3-DVT NOPOP FROM SS BOM 20161220
(50 300) 0;
DISPLAY LEFT (50 300);
DISPLAY 0.638298 (50 300);
PAINT RED (50 300);
FORCENOTE
TP FAB1 CHANGE CAPACITY 0322
(50 350) 0;
DISPLAY LEFT (50 350);
DISPLAY 0.638298 (50 350);
PAINT RED (50 350);
FORCENOTE
TP FAB1 CHANGE CAP 0314
(400 1325) 0;
DISPLAY LEFT (400 1325);
DISPLAY 1.021277 (400 1325);
PAINT RED (400 1325);
FORCENOTE
TP FAB3-DVT NOPOP FROM SS BOM 20161220
(500 2200) 0;
DISPLAY LEFT (500 2200);
DISPLAY 0.638298 (500 2200);
PAINT RED (500 2200);
FORCENOTE
TP FAB1 CHANGE CAP 0311
(500 2250) 0;
DISPLAY LEFT (500 2250);
DISPLAY 0.638298 (500 2250);
PAINT RED (500 2250);
FORCENOTE
PVDDQ CPU CAVITY CAPS
(-1375 2425) 0;
DISPLAY LEFT (-1375 2425);
DISPLAY 1.021277 (-1375 2425);
PAINT PURPLE (-1375 2425);
FORCENOTE
TP FAB1 CHANGE CAP 0311
(-2400 2400) 0;
DISPLAY LEFT (-2400 2400);
DISPLAY 0.638298 (-2400 2400);
PAINT RED (-2400 2400);
FORCENOTE
ROUTE AS DIFF PAIR
(-895 1980) 0;
DISPLAY LEFT (-895 1980);
DISPLAY 0.808511 (-895 1980);
PAINT PURPLE (-895 1980);
FORCENOTE
10MIL WIDTH
(-820 1880) 0;
DISPLAY LEFT (-820 1880);
DISPLAY 0.808511 (-820 1880);
PAINT PURPLE (-820 1880);
FORCENOTE
TP FAB3-DVT NOPOP FROM SS BOM 20161220
(2700 150) 0;
DISPLAY LEFT (2700 150);
DISPLAY 0.638298 (2700 150);
PAINT RED (2700 150);
FORCENOTE
CAPS TO BE PLACED BETWEEN DIMMS
(2295 3255) 0;
DISPLAY LEFT (2295 3255);
DISPLAY 1.021277 (2295 3255);
PAINT PURPLE (2295 3255);
FORCENOTE
TOP SIDE: 603
(-948 3192) 0;
DISPLAY LEFT (-948 3192);
DISPLAY 0.638298 (-948 3192);
PAINT PURPLE (-948 3192);
FORCENOTE
PVDDQ_KLM VOLTAGE SENSE
(-1570 1630) 0;
DISPLAY LEFT (-1570 1630);
PAINT PURPLE (-1570 1630);
FORCENOTE
ROOM = VDDQ_KLM_PWR_VR
(-2390 -1385) 0;
DISPLAY LEFT (-2390 -1385);
DISPLAY 2.446809 (-2390 -1385);
PAINT PURPLE (-2390 -1385);
FORCENOTE
TP FAB1 CHANGE CAP 0322
(-2450 -1225) 0;
DISPLAY LEFT (-2450 -1225);
DISPLAY 1.021277 (-2450 -1225);
PAINT RED (-2450 -1225);
FORCENOTE
5MIL SPACING
(-845 1830) 0;
DISPLAY LEFT (-845 1830);
DISPLAY 0.808511 (-845 1830);
PAINT PURPLE (-845 1830);
FORCENOTE
CAD NOTE:
(3100 -900) 0;
DISPLAY LEFT (3100 -900);
DISPLAY 1.021277 (3100 -900);
PAINT PURPLE (3100 -900);
FORCENOTE
ROOM=VDDQ_KLM_CPU1
(-2375 2225) 0;
DISPLAY LEFT (-2375 2225);
DISPLAY 1.021277 (-2375 2225);
PAINT PURPLE (-2375 2225);
QUIT
